FILE_TYPE = MACRO_DRAWING;
SET COLOR_WIRE YELLOW;
SET COLOR_PROP ORANGE;
SET COLOR_DOT WHITE;
SET COLOR_ARC YELLOW;
SET COLOR_BODY GREEN;
SET COLOR_NOTE PURPLE;
SET PROP_DISPLAY VALUE;
SET PAGE_NUMBER P297;
FORCEADD OFFPAGE..1
(1325 825);
FORCEPROP 2 LAST $XR0 224 
J 0
(1073 825);
DISPLAY 0.638298 (1073 825);
PAINT MONO (1073 825);
FORCEPROP 2 LAST CDS_LIB standard
J 0
(1325 825);
DISPLAY INVISIBLE (1325 825);
FORCEPROP 1 LAST OFFPAGE TRUE
J 0
(1650 700);
DISPLAY 0.872340 (1650 700);
PAINT GREEN (1650 700);
DISPLAY INVISIBLE (1650 700);
FORCEPROP 1 LAST COMMENT_BODY TRUE
J 0
(1450 725);
DISPLAY 0.872340 (1450 725);
PAINT GREEN (1450 725);
DISPLAY INVISIBLE (1450 725);
FORCEPROP 2 LAST PATH I156
J 0
(1075 875);
DISPLAY 1.021277 (1075 875);
DISPLAY INVISIBLE (1075 875);
FORCEADD Q_RES..1
(2275 825);
FORCEPROP 1 LAST PART_NUMBER CS00002JB13
J 0
(2175 875);
DISPLAY 0.404255 (2175 875);
DISPLAY INVISIBLE (2175 875);
FORCEPROP 1 LAST VALUE 0
J 2
(2425 825);
DISPLAY 0.510638 (2425 825);
FORCEPROP 1 LAST TOLERANCE 5%
J 0
(2450 825);
DISPLAY 0.510638 (2450 825);
FORCEPROP 1 LAST MATERIAL CHIP
J 0
(2525 825);
DISPLAY 0.510638 (2525 825);
FORCEPROP 1 LAST $LOCATION R2350
J 0
(2050 825);
DISPLAY 0.787234 (2050 825);
FORCEPROP 1 LASTPIN (2175 825) $PN 1
J 0
(2187 837);
DISPLAY 0.787234 (2187 837);
PAINT MONO (2187 837);
FORCEPROP 1 LASTPIN (2375 825) $PN 2
J 0
(2337 837);
DISPLAY 0.787234 (2337 837);
PAINT MONO (2337 837);
FORCEPROP 1 LAST PATH I157
J 0
(2225 975);
DISPLAY 0.978723 (2225 975);
PAINT WHITE (2225 975);
DISPLAY INVISIBLE (2225 975);
FORCEPROP 2 LAST CDS_LIB pure_quanta
J 0
(2275 825);
DISPLAY INVISIBLE (2275 825);
FORCEPROP 1 LAST WATTAGE 1/16W
J 2
(2400 900);
DISPLAY 0.404255 (2400 900);
DISPLAY INVISIBLE (2400 900);
FORCEPROP 1 LAST PACK_TYPE 0402LF
J 0
(2175 900);
DISPLAY 0.404255 (2175 900);
DISPLAY INVISIBLE (2175 900);
FORCEPROP 0 LAST CDS_LOCATION R2350
J 0
(2075 875);
DISPLAY 1.021277 (2075 875);
DISPLAY INVISIBLE (2075 875);
FORCEPROP 0 LAST $SEC 1
J 0
(2075 875);
DISPLAY 0.680851 (2075 875);
PAINT MONO (2075 875);
DISPLAY INVISIBLE (2075 875);
FORCEPROP 0 LAST CDS_SEC 1
J 0
(2075 875);
DISPLAY 1.021277 (2075 875);
DISPLAY INVISIBLE (2075 875);
FORCEADD OFFPAGE..1
(1675 1225);
FORCEPROP 2 LAST $XR2 215 
J 0
(1183 1225);
DISPLAY 0.638298 (1183 1225);
PAINT MONO (1183 1225);
FORCEPROP 2 LAST $XR1 183 
J 0
(1303 1225);
DISPLAY 0.638298 (1303 1225);
PAINT MONO (1303 1225);
FORCEPROP 2 LAST $XR0 191 
J 0
(1423 1225);
DISPLAY 0.638298 (1423 1225);
PAINT MONO (1423 1225);
FORCEPROP 2 LAST PATH I158
J 0
(1425 1275);
DISPLAY 1.021277 (1425 1275);
DISPLAY INVISIBLE (1425 1275);
FORCEPROP 1 LAST COMMENT_BODY TRUE
J 0
(1800 1125);
DISPLAY 0.872340 (1800 1125);
PAINT GREEN (1800 1125);
DISPLAY INVISIBLE (1800 1125);
FORCEPROP 1 LAST OFFPAGE TRUE
J 0
(2000 1100);
DISPLAY 0.872340 (2000 1100);
PAINT GREEN (2000 1100);
DISPLAY INVISIBLE (2000 1100);
FORCEPROP 2 LAST CDS_LIB standard
J 0
(1675 1225);
DISPLAY INVISIBLE (1675 1225);
FORCEADD Q_RES..2
R 2
(1800 1525);
FORCEPROP 1 LAST PART_NUMBER CS31002FB08
J 2
(1760 1350);
DISPLAY 0.510638 (1760 1350);
DISPLAY INVISIBLE (1760 1350);
FORCEPROP 1 LAST PACK_TYPE 0402LF
J 2
(1760 1400);
DISPLAY 0.510638 (1760 1400);
FORCEPROP 1 LAST TOLERANCE 1%
J 2
(1755 1550);
DISPLAY 0.510638 (1755 1550);
FORCEPROP 1 LAST WATTAGE 1/16W
J 2
(1760 1500);
DISPLAY 0.510638 (1760 1500);
FORCEPROP 1 LAST MATERIAL CHIP
J 2
(1760 1450);
DISPLAY 0.510638 (1760 1450);
FORCEPROP 1 LAST VALUE 10K
J 2
(1755 1600);
DISPLAY 0.510638 (1755 1600);
FORCEPROP 1 LAST $LOCATION R2304
J 2
(1755 1650);
DISPLAY 0.978723 (1755 1650);
FORCEPROP 1 LASTPIN (1800 1625) $PN 1
J 2
(1795 1587);
DISPLAY 0.787234 (1795 1587);
PAINT MONO (1795 1587);
FORCEPROP 1 LASTPIN (1800 1425) $PN 2
J 2
(1795 1435);
DISPLAY 0.787234 (1795 1435);
PAINT MONO (1795 1435);
FORCEPROP 1 LAST PATH I159
J 2
(1750 1700);
DISPLAY 0.978723 (1750 1700);
PAINT WHITE (1750 1700);
DISPLAY INVISIBLE (1750 1700);
FORCEPROP 2 LAST CDS_LIB pure_quanta
J 2
(1800 1525);
DISPLAY INVISIBLE (1800 1525);
FORCEPROP 0 LAST CDS_LOCATION R2304
J 2
(1750 1700);
DISPLAY 1.021277 (1750 1700);
DISPLAY INVISIBLE (1750 1700);
FORCEPROP 0 LAST $SEC 1
J 2
(1750 1700);
DISPLAY 0.680851 (1750 1700);
PAINT MONO (1750 1700);
DISPLAY INVISIBLE (1750 1700);
FORCEPROP 0 LAST CDS_SEC 1
J 2
(1750 1700);
DISPLAY 1.021277 (1750 1700);
DISPLAY INVISIBLE (1750 1700);
FORCEADD UNIVERSAL_POWER..1
(1800 1775);
FORCEPROP 3 LASTPIN (1800 1725) SIG_NAME P3V3_AUX\g
J 0
(1810 1735);
DISPLAY 0.659574 (1810 1735);
PAINT MONO (1810 1735);
DISPLAY INVISIBLE (1810 1735);
FORCEPROP 1 LAST HDL_POWER P3V3_AUX
J 1
(1800 1825);
DISPLAY 0.872340 (1800 1825);
PAINT GREEN (1800 1825);
FORCEPROP 1 LAST PATH I160
J 0
(1850 1800);
DISPLAY 0.872340 (1850 1800);
PAINT AQUA (1850 1800);
DISPLAY INVISIBLE (1850 1800);
FORCEPROP 2 LAST CDS_LIB logical_power
J 0
(1800 1775);
DISPLAY INVISIBLE (1800 1775);
FORCEADD 74LVC1G126SE7..1
(3675 875);
FORCEPROP 1 LAST PART_NUMBER AL1G0126009
J 0
(3781 559);
DISPLAY 0.723404 (3781 559);
PAINT GREEN (3781 559);
DISPLAY INVISIBLE (3781 559);
FORCEPROP 1 LAST MATERIAL IC
J 0
(3781 432);
DISPLAY 0.723404 (3781 432);
PAINT GREEN (3781 432);
FORCEPROP 2 LAST PART_TYPE SMLF
J 0
(3800 1050);
DISPLAY 0.638298 (3800 1050);
FORCEPROP 2 LAST VALUE 74LVC1G126SE-7
J 0
(3800 1000);
DISPLAY 0.638298 (3800 1000);
FORCEPROP 1 LAST $LOCATION U145
J 0
(3781 706);
DISPLAY 0.723404 (3781 706);
PAINT GREEN (3781 706);
FORCEPROP 2 LASTPIN (3425 925) $PN 2
J 2
(3415 935);
DISPLAY 0.680851 (3415 935);
PAINT MONO (3415 935);
FORCEPROP 2 LASTPIN (3675 625) $PN 3
R 1
J 2
(3665 615);
DISPLAY 0.680851 (3665 615);
PAINT MONO (3665 615);
FORCEPROP 2 LASTPIN (3425 825) $PN 1
J 2
(3415 835);
DISPLAY 0.680851 (3415 835);
PAINT MONO (3415 835);
FORCEPROP 2 LASTPIN (3675 1125) $PN 5
R 1
J 0
(3665 1135);
DISPLAY 0.680851 (3665 1135);
PAINT MONO (3665 1135);
FORCEPROP 2 LASTPIN (3925 875) $PN 4
J 0
(3935 885);
DISPLAY 0.680851 (3935 885);
PAINT MONO (3935 885);
FORCEPROP 1 LAST PATH I163
J 0
(3675 875);
DISPLAY 0.723404 (3675 875);
PAINT GREEN (3675 875);
DISPLAY INVISIBLE (3675 875);
FORCEPROP 2 LAST SEC_TYPE 
J 0
(3800 1100);
DISPLAY 1.021277 (3800 1100);
DISPLAY INVISIBLE (3800 1100);
FORCEPROP 2 LAST CDS_LIB pure_quanta
J 0
(3675 875);
DISPLAY INVISIBLE (3675 875);
FORCEPROP 1 LAST CDS_LMAN_SYM_OUTLINE -100,100,100,-100
J 0
(3675 875);
DISPLAY 0.468085 (3675 875);
PAINT GREEN (3675 875);
DISPLAY INVISIBLE (3675 875);
FORCEPROP 1 LAST NEEDS_NO_SIZE TRUE
J 0
(3675 875);
DISPLAY 0.723404 (3675 875);
PAINT GREEN (3675 875);
DISPLAY INVISIBLE (3675 875);
FORCEPROP 0 LAST CDS_LOCATION U145
J 0
(3800 1100);
DISPLAY 1.021277 (3800 1100);
DISPLAY INVISIBLE (3800 1100);
FORCEPROP 2 LAST SEC 1
J 0
(3800 1100);
DISPLAY 0.680851 (3800 1100);
PAINT MONO (3800 1100);
DISPLAY INVISIBLE (3800 1100);
FORCEADD UNIVERSAL_GND..1
(3675 475);
FORCEPROP 3 LASTPIN (3675 525) SIG_NAME GND\g
J 0
(3685 535);
DISPLAY 0.659574 (3685 535);
PAINT MONO (3685 535);
DISPLAY INVISIBLE (3685 535);
FORCEPROP 1 LAST PATH I164
J 0
(3750 475);
DISPLAY 0.872340 (3750 475);
PAINT AQUA (3750 475);
DISPLAY INVISIBLE (3750 475);
FORCEPROP 1 LAST HDL_POWER GND
J 1
(3700 400);
DISPLAY 0.872340 (3700 400);
PAINT GREEN (3700 400);
DISPLAY INVISIBLE (3700 400);
FORCEPROP 2 LAST CDS_LIB logical_power
J 0
(3675 475);
DISPLAY INVISIBLE (3675 475);
FORCEADD Q_RES..2
(4350 650);
FORCEPROP 1 LAST PART_NUMBER CS41002FB09
J 0
(4390 525);
DISPLAY 0.638298 (4390 525);
DISPLAY INVISIBLE (4390 525);
FORCEPROP 1 LAST PACK_TYPE 0402LF
J 0
(4390 475);
DISPLAY 0.638298 (4390 475);
FORCEPROP 1 LAST VALUE 100K
J 0
(4395 725);
DISPLAY 0.638298 (4395 725);
FORCEPROP 1 LAST WATTAGE 1/16W
J 0
(4390 625);
DISPLAY 0.638298 (4390 625);
FORCEPROP 1 LAST MATERIAL CHIP
J 0
(4390 575);
DISPLAY 0.638298 (4390 575);
FORCEPROP 1 LAST TOLERANCE 1%
J 0
(4395 675);
DISPLAY 0.638298 (4395 675);
FORCEPROP 1 LAST $LOCATION R2457
J 0
(4395 775);
DISPLAY 0.638298 (4395 775);
FORCEPROP 1 LASTPIN (4350 750) $PN 1
J 0
(4355 712);
DISPLAY 0.787234 (4355 712);
PAINT MONO (4355 712);
FORCEPROP 1 LASTPIN (4350 550) $PN 2
J 0
(4355 560);
DISPLAY 0.787234 (4355 560);
PAINT MONO (4355 560);
FORCEPROP 1 LAST PATH I165
J 0
(4400 825);
DISPLAY 0.978723 (4400 825);
PAINT WHITE (4400 825);
DISPLAY INVISIBLE (4400 825);
FORCEPROP 2 LAST CDS_LIB pure_quanta
J 0
(4350 650);
DISPLAY INVISIBLE (4350 650);
FORCEPROP 0 LAST CDS_LOCATION R2457
J 0
(4400 825);
DISPLAY 1.021277 (4400 825);
DISPLAY INVISIBLE (4400 825);
FORCEPROP 0 LAST $SEC 1
J 0
(4400 825);
DISPLAY 0.680851 (4400 825);
PAINT MONO (4400 825);
DISPLAY INVISIBLE (4400 825);
FORCEPROP 0 LAST CDS_SEC 1
J 0
(4400 825);
DISPLAY 1.021277 (4400 825);
DISPLAY INVISIBLE (4400 825);
FORCEADD UNIVERSAL_GND..1
(4350 450);
FORCEPROP 3 LASTPIN (4350 500) SIG_NAME GND\g
J 0
(4360 510);
DISPLAY 0.659574 (4360 510);
PAINT MONO (4360 510);
DISPLAY INVISIBLE (4360 510);
FORCEPROP 1 LAST PATH I166
J 0
(4425 450);
DISPLAY 0.872340 (4425 450);
PAINT AQUA (4425 450);
DISPLAY INVISIBLE (4425 450);
FORCEPROP 1 LAST HDL_POWER GND
J 1
(4375 375);
DISPLAY 0.872340 (4375 375);
PAINT GREEN (4375 375);
DISPLAY INVISIBLE (4375 375);
FORCEPROP 2 LAST CDS_LIB logical_power
J 0
(4350 450);
DISPLAY INVISIBLE (4350 450);
FORCEADD OFFPAGE..2
(4475 875);
FORCEPROP 2 LAST $XR1 193 
J 0
(4784 875);
DISPLAY 0.638298 (4784 875);
PAINT MONO (4784 875);
FORCEPROP 2 LAST $XR0 192 
J 0
(4664 875);
DISPLAY 0.638298 (4664 875);
PAINT MONO (4664 875);
FORCEPROP 1 LAST OFFPAGE TRUE
J 0
(4800 750);
DISPLAY 0.872340 (4800 750);
DISPLAY INVISIBLE (4800 750);
FORCEPROP 1 LAST COMMENT_BODY TRUE
J 0
(4430 780);
DISPLAY 0.872340 (4430 780);
PAINT GREEN (4430 780);
DISPLAY INVISIBLE (4430 780);
FORCEPROP 2 LAST PATH I167
J 0
(4800 925);
DISPLAY 1.021277 (4800 925);
DISPLAY INVISIBLE (4800 925);
FORCEPROP 2 LAST CDS_LIB standard
J 0
(4475 875);
DISPLAY INVISIBLE (4475 875);
FORCEADD UNIVERSAL_POWER..1
(2675 2000);
FORCEPROP 3 LASTPIN (2675 1950) SIG_NAME P3V3_AUX\g
J 0
(2685 1960);
DISPLAY 0.659574 (2685 1960);
PAINT MONO (2685 1960);
DISPLAY INVISIBLE (2685 1960);
FORCEPROP 1 LAST HDL_POWER P3V3_AUX
J 1
(2675 2050);
DISPLAY 0.872340 (2675 2050);
PAINT GREEN (2675 2050);
FORCEPROP 1 LAST PATH I168
J 0
(2725 2025);
DISPLAY 0.872340 (2725 2025);
PAINT AQUA (2725 2025);
DISPLAY INVISIBLE (2725 2025);
FORCEPROP 2 LAST CDS_LIB logical_power
J 0
(2675 2000);
DISPLAY INVISIBLE (2675 2000);
FORCEADD Q_RES..2
(2675 1800);
FORCEPROP 1 LAST PART_NUMBER CS31002FB08
J 0
(2715 1625);
DISPLAY 0.510638 (2715 1625);
DISPLAY INVISIBLE (2715 1625);
FORCEPROP 1 LAST VALUE 10K
J 0
(2720 1875);
DISPLAY 0.510638 (2720 1875);
FORCEPROP 1 LAST TOLERANCE 1%
J 0
(2720 1825);
DISPLAY 0.510638 (2720 1825);
FORCEPROP 1 LAST WATTAGE 1/16W
J 0
(2715 1775);
DISPLAY 0.510638 (2715 1775);
FORCEPROP 1 LAST MATERIAL CHIP
J 0
(2715 1725);
DISPLAY 0.510638 (2715 1725);
FORCEPROP 1 LAST PACK_TYPE 0402LF
J 0
(2715 1675);
DISPLAY 0.510638 (2715 1675);
FORCEPROP 1 LAST $LOCATION R2282
J 0
(2720 1925);
DISPLAY 0.978723 (2720 1925);
FORCEPROP 1 LASTPIN (2675 1900) $PN 1
J 0
(2680 1862);
DISPLAY 0.787234 (2680 1862);
PAINT MONO (2680 1862);
FORCEPROP 1 LASTPIN (2675 1700) $PN 2
J 0
(2680 1710);
DISPLAY 0.787234 (2680 1710);
PAINT MONO (2680 1710);
FORCEPROP 1 LAST PATH I169
J 0
(2725 1975);
DISPLAY 0.978723 (2725 1975);
PAINT WHITE (2725 1975);
DISPLAY INVISIBLE (2725 1975);
FORCEPROP 2 LAST CDS_LIB pure_quanta
J 0
(2675 1800);
DISPLAY INVISIBLE (2675 1800);
FORCEPROP 0 LAST CDS_LOCATION R2282
J 0
(2725 1975);
DISPLAY 1.021277 (2725 1975);
DISPLAY INVISIBLE (2725 1975);
FORCEPROP 0 LAST $SEC 1
J 0
(2725 1975);
DISPLAY 0.680851 (2725 1975);
PAINT MONO (2725 1975);
DISPLAY INVISIBLE (2725 1975);
FORCEPROP 0 LAST CDS_SEC 1
J 0
(2725 1975);
DISPLAY 1.021277 (2725 1975);
DISPLAY INVISIBLE (2725 1975);
FORCEADD Q_CAP..1
(3850 1400);
FORCEPROP 1 LAST PART_NUMBER CH4104K1B00
J 0
(3900 1250);
DISPLAY 0.510638 (3900 1250);
DISPLAY INVISIBLE (3900 1250);
FORCEPROP 1 LAST PACK_TYPE 0402
J 0
(3900 1200);
DISPLAY 0.510638 (3900 1200);
FORCEPROP 1 LAST VOLTAGE 25V
J 0
(3900 1400);
DISPLAY 0.510638 (3900 1400);
FORCEPROP 1 LAST VALUE 0.1UF
J 0
(3900 1450);
DISPLAY 0.510638 (3900 1450);
FORCEPROP 1 LAST TOLERANCE 10%
J 0
(3900 1350);
DISPLAY 0.510638 (3900 1350);
FORCEPROP 1 LAST MATERIAL X7R
J 0
(3900 1300);
DISPLAY 0.510638 (3900 1300);
FORCEPROP 1 LAST $LOCATION C1614
J 0
(3900 1500);
DISPLAY 0.978723 (3900 1500);
FORCEPROP 1 LASTPIN (3850 1500) $PN 1
J 0
(3860 1480);
DISPLAY 0.787234 (3860 1480);
PAINT MONO (3860 1480);
FORCEPROP 1 LASTPIN (3850 1300) $PN 2
J 0
(3860 1280);
DISPLAY 0.787234 (3860 1280);
PAINT MONO (3860 1280);
FORCEPROP 1 LAST PATH I170
J 0
(3900 1550);
DISPLAY 0.978723 (3900 1550);
PAINT WHITE (3900 1550);
DISPLAY INVISIBLE (3900 1550);
FORCEPROP 2 LAST CDS_LIB pure_quanta
J 2
(3850 1400);
DISPLAY INVISIBLE (3850 1400);
FORCEPROP 0 LAST CDS_LOCATION C1614
J 0
(3900 1550);
DISPLAY 1.021277 (3900 1550);
DISPLAY INVISIBLE (3900 1550);
FORCEPROP 0 LAST $SEC 1
J 0
(3900 1550);
DISPLAY 0.680851 (3900 1550);
PAINT MONO (3900 1550);
DISPLAY INVISIBLE (3900 1550);
FORCEPROP 0 LAST CDS_SEC 1
J 0
(3900 1550);
DISPLAY 1.021277 (3900 1550);
DISPLAY INVISIBLE (3900 1550);
FORCEADD UNIVERSAL_GND..1
(3850 1175);
FORCEPROP 3 LASTPIN (3850 1225) SIG_NAME GND\g
J 0
(3860 1235);
DISPLAY 0.659574 (3860 1235);
PAINT MONO (3860 1235);
DISPLAY INVISIBLE (3860 1235);
FORCEPROP 1 LAST PATH I171
J 0
(3925 1175);
DISPLAY 0.872340 (3925 1175);
PAINT AQUA (3925 1175);
DISPLAY INVISIBLE (3925 1175);
FORCEPROP 1 LAST HDL_POWER GND
J 1
(3875 1100);
DISPLAY 0.872340 (3875 1100);
PAINT GREEN (3875 1100);
DISPLAY INVISIBLE (3875 1100);
FORCEPROP 2 LAST CDS_LIB logical_power
J 0
(3850 1175);
DISPLAY INVISIBLE (3850 1175);
FORCEADD UNIVERSAL_POWER..1
(3850 1675);
FORCEPROP 3 LASTPIN (3850 1625) SIG_NAME P3V3_AUX\g
J 0
(3860 1635);
DISPLAY 0.659574 (3860 1635);
PAINT MONO (3860 1635);
DISPLAY INVISIBLE (3860 1635);
FORCEPROP 1 LAST HDL_POWER P3V3_AUX
J 1
(3850 1725);
DISPLAY 0.872340 (3850 1725);
PAINT GREEN (3850 1725);
FORCEPROP 1 LAST PATH I172
J 0
(3900 1700);
DISPLAY 0.872340 (3900 1700);
PAINT AQUA (3900 1700);
DISPLAY INVISIBLE (3900 1700);
FORCEPROP 2 LAST CDS_LIB logical_power
J 0
(3850 1675);
DISPLAY INVISIBLE (3850 1675);
FORCEADD Q_CAP..1
(2600 2825);
FORCEPROP 1 LAST PART_NUMBER CH6223MEA01
J 0
(2650 2675);
DISPLAY 0.638298 (2650 2675);
DISPLAY INVISIBLE (2650 2675);
FORCEPROP 1 LAST PACK_TYPE C0805
J 0
(2650 2625);
DISPLAY 0.638298 (2650 2625);
FORCEPROP 1 LAST VALUE 22UF
J 0
(2650 2875);
DISPLAY 0.638298 (2650 2875);
FORCEPROP 1 LAST VOLTAGE 16V
J 0
(2650 2825);
DISPLAY 0.638298 (2650 2825);
FORCEPROP 1 LAST MATERIAL X6S
J 0
(2650 2725);
DISPLAY 0.638298 (2650 2725);
FORCEPROP 1 LAST TOLERANCE 20%
J 0
(2650 2775);
DISPLAY 0.638298 (2650 2775);
FORCEPROP 1 LAST $LOCATION C1277
J 0
(2650 2925);
DISPLAY 0.787234 (2650 2925);
FORCEPROP 1 LASTPIN (2600 2925) $PN 1
J 0
(2610 2905);
DISPLAY 0.787234 (2610 2905);
FORCEPROP 1 LASTPIN (2600 2725) $PN 2
J 0
(2610 2705);
DISPLAY 0.787234 (2610 2705);
FORCEPROP 2 LAST CDS_LIB pure_quanta
J 0
(2600 2825);
PAINT MONO (2600 2825);
DISPLAY INVISIBLE (2600 2825);
FORCEPROP 1 LAST PATH I237
J 0
(2650 2975);
DISPLAY 0.978723 (2650 2975);
PAINT WHITE (2650 2975);
DISPLAY INVISIBLE (2650 2975);
FORCEPROP 2 LAST CDS_LOCATION C1277
J 0
(2650 3025);
DISPLAY 1.021277 (2650 3025);
DISPLAY INVISIBLE (2650 3025);
FORCEPROP 2 LAST $SEC 1
J 0
(2650 3025);
DISPLAY 0.680851 (2650 3025);
PAINT MONO (2650 3025);
DISPLAY INVISIBLE (2650 3025);
FORCEPROP 2 LAST CDS_SEC 1
J 0
(2650 3025);
DISPLAY 1.021277 (2650 3025);
DISPLAY INVISIBLE (2650 3025);
FORCEADD UNIVERSAL_POWER..1
(3775 4850);
FORCEPROP 3 LASTPIN (3775 4800) SIG_NAME P3V3_E1S_0\g
J 0
(3785 4810);
DISPLAY 0.659574 (3785 4810);
PAINT MONO (3785 4810);
DISPLAY INVISIBLE (3785 4810);
FORCEPROP 1 LAST HDL_POWER P3V3_E1S_0
J 1
(3775 4900);
DISPLAY 0.872340 (3775 4900);
PAINT GREEN (3775 4900);
FORCEPROP 1 LAST PATH I238
J 0
(3825 4875);
DISPLAY 0.872340 (3825 4875);
PAINT AQUA (3825 4875);
DISPLAY INVISIBLE (3825 4875);
FORCEPROP 2 LAST CDS_LIB logical_power
J 0
(3775 4850);
DISPLAY INVISIBLE (3775 4850);
FORCEADD OFFPAGE..4
(2875 4350);
FORCEPROP 2 LAST $XR0 194 
J 0
(3061 4350);
DISPLAY 0.638298 (3061 4350);
PAINT MONO (3061 4350);
FORCEPROP 2 LAST CDS_LIB standard
J 0
(2875 4350);
PAINT MONO (2875 4350);
DISPLAY INVISIBLE (2875 4350);
FORCEPROP 1 LAST OFFPAGE TRUE
J 0
(3200 4225);
DISPLAY 0.872340 (3200 4225);
PAINT GREEN (3200 4225);
DISPLAY INVISIBLE (3200 4225);
FORCEPROP 1 LAST COMMENT_BODY TRUE
J 0
(2850 4250);
DISPLAY 0.872340 (2850 4250);
PAINT GREEN (2850 4250);
DISPLAY INVISIBLE (2850 4250);
FORCEPROP 2 LAST PATH I240
J 0
(3075 4400);
DISPLAY 1.021277 (3075 4400);
DISPLAY INVISIBLE (3075 4400);
FORCEADD OFFPAGE..3
(2875 4300);
FORCEPROP 2 LAST $XR0 194 
J 0
(3089 4300);
DISPLAY 0.638298 (3089 4300);
PAINT MONO (3089 4300);
FORCEPROP 2 LAST CDS_LIB standard
J 0
(2875 4300);
PAINT MONO (2875 4300);
DISPLAY INVISIBLE (2875 4300);
FORCEPROP 1 LAST OFFPAGE TRUE
J 0
(3200 4175);
DISPLAY 0.872340 (3200 4175);
DISPLAY INVISIBLE (3200 4175);
FORCEPROP 1 LAST COMMENT_BODY TRUE
J 0
(2825 4200);
DISPLAY 0.872340 (2825 4200);
PAINT GREEN (2825 4200);
DISPLAY INVISIBLE (2825 4200);
FORCEPROP 2 LAST PATH I241
J 0
(3250 4350);
DISPLAY 1.021277 (3250 4350);
DISPLAY INVISIBLE (3250 4350);
FORCEADD UNIVERSAL_POWER..1
(2300 4825);
FORCEPROP 3 LASTPIN (2300 4775) SIG_NAME P3V3_E1S_0\g
J 0
(2310 4785);
DISPLAY 0.659574 (2310 4785);
PAINT MONO (2310 4785);
DISPLAY INVISIBLE (2310 4785);
FORCEPROP 1 LAST HDL_POWER P3V3_E1S_0
J 1
(2300 4875);
DISPLAY 0.872340 (2300 4875);
PAINT GREEN (2300 4875);
FORCEPROP 2 LAST CDS_LIB logical_power
J 0
(2300 4825);
PAINT MONO (2300 4825);
DISPLAY INVISIBLE (2300 4825);
FORCEPROP 1 LAST PATH I242
J 0
(2350 4850);
DISPLAY 0.872340 (2350 4850);
PAINT AQUA (2350 4850);
DISPLAY INVISIBLE (2350 4850);
FORCEADD OFFPAGE..2
(4075 4150);
FORCEPROP 2 LAST $XR0 183 
J 0
(4264 4150);
DISPLAY 0.638298 (4264 4150);
PAINT MONO (4264 4150);
FORCEPROP 2 LAST CDS_LIB standard
J 0
(4075 4150);
DISPLAY INVISIBLE (4075 4150);
FORCEPROP 1 LAST OFFPAGE TRUE
J 0
(4400 4025);
DISPLAY 0.872340 (4400 4025);
PAINT GREEN (4400 4025);
DISPLAY INVISIBLE (4400 4025);
FORCEPROP 1 LAST COMMENT_BODY TRUE
J 0
(4030 4055);
DISPLAY 0.872340 (4030 4055);
PAINT GREEN (4030 4055);
DISPLAY INVISIBLE (4030 4055);
FORCEPROP 2 LAST PATH I244
J 0
(4275 4200);
DISPLAY 1.021277 (4275 4200);
DISPLAY INVISIBLE (4275 4200);
FORCEADD Q_CAP..1
(4600 2825);
FORCEPROP 1 LAST PART_NUMBER CH4104K1B00
J 0
(4650 2675);
DISPLAY 0.808511 (4650 2675);
DISPLAY INVISIBLE (4650 2675);
FORCEPROP 1 LAST VALUE 0.1UF
J 0
(4650 2875);
DISPLAY 0.638298 (4650 2875);
FORCEPROP 1 LAST VOLTAGE 25V
J 0
(4650 2825);
DISPLAY 0.638298 (4650 2825);
FORCEPROP 1 LAST MATERIAL X7R
J 0
(4650 2725);
DISPLAY 0.638298 (4650 2725);
FORCEPROP 1 LAST PACK_TYPE 0402
J 0
(4650 2675);
DISPLAY 0.638298 (4650 2675);
FORCEPROP 1 LAST TOLERANCE 10%
J 0
(4650 2775);
DISPLAY 0.638298 (4650 2775);
FORCEPROP 1 LAST $LOCATION C1283
J 0
(4650 2925);
DISPLAY 0.787234 (4650 2925);
FORCEPROP 1 LASTPIN (4600 2925) $PN 1
J 0
(4610 2905);
DISPLAY 0.787234 (4610 2905);
FORCEPROP 1 LASTPIN (4600 2725) $PN 2
J 0
(4610 2705);
DISPLAY 0.787234 (4610 2705);
FORCEPROP 2 LAST CDS_LIB pure_quanta
J 0
(4600 2825);
PAINT MONO (4600 2825);
DISPLAY INVISIBLE (4600 2825);
FORCEPROP 1 LAST PATH I245
J 0
(4650 2975);
DISPLAY 0.978723 (4650 2975);
PAINT WHITE (4650 2975);
DISPLAY INVISIBLE (4650 2975);
FORCEPROP 2 LAST CDS_LOCATION C1283
J 0
(4650 3025);
DISPLAY 1.021277 (4650 3025);
DISPLAY INVISIBLE (4650 3025);
FORCEPROP 2 LAST $SEC 1
J 0
(4650 3025);
DISPLAY 0.680851 (4650 3025);
PAINT MONO (4650 3025);
DISPLAY INVISIBLE (4650 3025);
FORCEPROP 2 LAST CDS_SEC 1
J 0
(4650 3025);
DISPLAY 1.021277 (4650 3025);
DISPLAY INVISIBLE (4650 3025);
FORCEADD UNIVERSAL_POWER..1
(4350 3175);
FORCEPROP 3 LASTPIN (4350 3125) SIG_NAME P3V3_E1S_0\g
J 0
(4360 3135);
DISPLAY 0.659574 (4360 3135);
PAINT MONO (4360 3135);
DISPLAY INVISIBLE (4360 3135);
FORCEPROP 1 LAST HDL_POWER P3V3_E1S_0
J 1
(4350 3225);
DISPLAY 0.872340 (4350 3225);
PAINT GREEN (4350 3225);
FORCEPROP 2 LAST CDS_LIB logical_power
J 0
(4350 3175);
PAINT MONO (4350 3175);
DISPLAY INVISIBLE (4350 3175);
FORCEPROP 1 LAST PATH I246
J 0
(4400 3200);
DISPLAY 0.872340 (4400 3200);
PAINT AQUA (4400 3200);
DISPLAY INVISIBLE (4400 3200);
FORCEADD Q_CAP..1
(4350 2825);
FORCEPROP 1 LAST PART_NUMBER CH4104K1B00
J 0
(4400 2675);
DISPLAY 0.808511 (4400 2675);
DISPLAY INVISIBLE (4400 2675);
FORCEPROP 1 LAST VOLTAGE 25V
J 0
(4400 2825);
DISPLAY 0.638298 (4400 2825);
FORCEPROP 1 LAST VALUE 0.1UF
J 0
(4400 2875);
DISPLAY 0.638298 (4400 2875);
FORCEPROP 1 LAST PACK_TYPE 0402
J 0
(4400 2675);
DISPLAY 0.638298 (4400 2675);
FORCEPROP 1 LAST MATERIAL X7R
J 0
(4400 2725);
DISPLAY 0.638298 (4400 2725);
FORCEPROP 1 LAST TOLERANCE 10%
J 0
(4400 2775);
DISPLAY 0.638298 (4400 2775);
FORCEPROP 1 LAST $LOCATION C1282
J 0
(4400 2925);
DISPLAY 0.787234 (4400 2925);
FORCEPROP 1 LASTPIN (4350 2925) $PN 1
J 0
(4360 2905);
DISPLAY 0.787234 (4360 2905);
FORCEPROP 1 LASTPIN (4350 2725) $PN 2
J 0
(4360 2705);
DISPLAY 0.787234 (4360 2705);
FORCEPROP 2 LAST CDS_LIB pure_quanta
J 0
(4350 2825);
PAINT MONO (4350 2825);
DISPLAY INVISIBLE (4350 2825);
FORCEPROP 1 LAST PATH I247
J 0
(4400 2975);
DISPLAY 0.978723 (4400 2975);
PAINT WHITE (4400 2975);
DISPLAY INVISIBLE (4400 2975);
FORCEPROP 2 LAST CDS_LOCATION C1282
J 0
(4400 3025);
DISPLAY 1.021277 (4400 3025);
DISPLAY INVISIBLE (4400 3025);
FORCEPROP 2 LAST $SEC 1
J 0
(4400 3025);
DISPLAY 0.680851 (4400 3025);
PAINT MONO (4400 3025);
DISPLAY INVISIBLE (4400 3025);
FORCEPROP 2 LAST CDS_SEC 1
J 0
(4400 3025);
DISPLAY 1.021277 (4400 3025);
DISPLAY INVISIBLE (4400 3025);
FORCEADD UNIVERSAL_GND..1
(4600 2475);
FORCEPROP 3 LASTPIN (4600 2525) SIG_NAME GND\g
J 0
(4610 2535);
DISPLAY 0.659574 (4610 2535);
PAINT MONO (4610 2535);
DISPLAY INVISIBLE (4610 2535);
FORCEPROP 2 LAST CDS_LIB logical_power
J 0
(4600 2475);
PAINT MONO (4600 2475);
DISPLAY INVISIBLE (4600 2475);
FORCEPROP 1 LAST HDL_POWER GND
J 1
(4625 2400);
DISPLAY 0.872340 (4625 2400);
PAINT GREEN (4625 2400);
DISPLAY INVISIBLE (4625 2400);
FORCEPROP 1 LAST PATH I248
J 0
(4675 2475);
DISPLAY 0.872340 (4675 2475);
PAINT AQUA (4675 2475);
DISPLAY INVISIBLE (4675 2475);
FORCEPROP 2 LAST ROOM IO_SLOT
J 1
(4375 2550);
DISPLAY 0.744681 (4375 2550);
DISPLAY INVISIBLE (4375 2550);
FORCEADD UNIVERSAL_GND..1
(3850 3625);
FORCEPROP 3 LASTPIN (3850 3675) SIG_NAME GND\g
J 0
(3860 3685);
DISPLAY 0.659574 (3860 3685);
PAINT MONO (3860 3685);
DISPLAY INVISIBLE (3860 3685);
FORCEPROP 2 LAST CDS_LIB logical_power
J 0
(3850 3625);
DISPLAY INVISIBLE (3850 3625);
FORCEPROP 1 LAST HDL_POWER GND
J 1
(3875 3550);
DISPLAY 0.872340 (3875 3550);
PAINT GREEN (3875 3550);
DISPLAY INVISIBLE (3875 3550);
FORCEPROP 1 LAST PATH I250
J 0
(3925 3625);
DISPLAY 0.872340 (3925 3625);
PAINT AQUA (3925 3625);
DISPLAY INVISIBLE (3925 3625);
FORCEPROP 2 LAST ROOM IO_SLOT
J 1
(3625 3700);
DISPLAY 0.744681 (3625 3700);
DISPLAY INVISIBLE (3625 3700);
FORCEADD OFFPAGE..4
(2875 4250);
FORCEPROP 2 LAST $XR0 191 
J 0
(3091 4250);
DISPLAY 0.638298 (3091 4250);
PAINT MONO (3091 4250);
FORCEPROP 2 LAST CDS_LIB standard
J 0
(2875 4250);
DISPLAY INVISIBLE (2875 4250);
FORCEPROP 1 LAST OFFPAGE TRUE
J 0
(3200 4125);
DISPLAY 0.872340 (3200 4125);
PAINT GREEN (3200 4125);
DISPLAY INVISIBLE (3200 4125);
FORCEPROP 1 LAST COMMENT_BODY TRUE
J 0
(2850 4150);
DISPLAY 0.872340 (2850 4150);
PAINT GREEN (2850 4150);
DISPLAY INVISIBLE (2850 4150);
FORCEPROP 2 LAST PATH I251
J 0
(3100 4300);
DISPLAY 1.021277 (3100 4300);
DISPLAY INVISIBLE (3100 4300);
FORCEADD Q_CAP..1
(3275 2825);
FORCEPROP 1 LAST PART_NUMBER CH4104K1B00
J 0
(3325 2675);
DISPLAY 0.808511 (3325 2675);
DISPLAY INVISIBLE (3325 2675);
FORCEPROP 1 LAST PACK_TYPE 0402
J 0
(3325 2675);
DISPLAY 0.638298 (3325 2675);
FORCEPROP 1 LAST VALUE 0.1UF
J 0
(3325 2875);
DISPLAY 0.638298 (3325 2875);
FORCEPROP 1 LAST VOLTAGE 25V
J 0
(3325 2825);
DISPLAY 0.638298 (3325 2825);
FORCEPROP 1 LAST MATERIAL X7R
J 0
(3325 2725);
DISPLAY 0.638298 (3325 2725);
FORCEPROP 1 LAST TOLERANCE 10%
J 0
(3325 2775);
DISPLAY 0.638298 (3325 2775);
FORCEPROP 1 LAST $LOCATION C1279
J 0
(3325 2925);
DISPLAY 0.787234 (3325 2925);
FORCEPROP 1 LASTPIN (3275 2925) $PN 1
J 0
(3285 2905);
DISPLAY 0.787234 (3285 2905);
FORCEPROP 1 LASTPIN (3275 2725) $PN 2
J 0
(3285 2705);
DISPLAY 0.787234 (3285 2705);
FORCEPROP 2 LAST CDS_LIB pure_quanta
J 0
(3275 2825);
PAINT MONO (3275 2825);
DISPLAY INVISIBLE (3275 2825);
FORCEPROP 1 LAST PATH I252
J 0
(3325 2975);
DISPLAY 0.978723 (3325 2975);
PAINT WHITE (3325 2975);
DISPLAY INVISIBLE (3325 2975);
FORCEPROP 2 LAST CDS_LOCATION C1279
J 0
(3325 3025);
DISPLAY 1.021277 (3325 3025);
DISPLAY INVISIBLE (3325 3025);
FORCEPROP 2 LAST $SEC 1
J 0
(3325 3025);
DISPLAY 0.680851 (3325 3025);
PAINT MONO (3325 3025);
DISPLAY INVISIBLE (3325 3025);
FORCEPROP 2 LAST CDS_SEC 1
J 0
(3325 3025);
DISPLAY 1.021277 (3325 3025);
DISPLAY INVISIBLE (3325 3025);
FORCEADD UNIVERSAL_GND..1
(3275 2475);
FORCEPROP 3 LASTPIN (3275 2525) SIG_NAME GND\g
J 0
(3285 2535);
DISPLAY 0.659574 (3285 2535);
PAINT MONO (3285 2535);
DISPLAY INVISIBLE (3285 2535);
FORCEPROP 2 LAST CDS_LIB logical_power
J 0
(3275 2475);
PAINT MONO (3275 2475);
DISPLAY INVISIBLE (3275 2475);
FORCEPROP 1 LAST HDL_POWER GND
J 1
(3300 2400);
DISPLAY 0.872340 (3300 2400);
PAINT GREEN (3300 2400);
DISPLAY INVISIBLE (3300 2400);
FORCEPROP 1 LAST PATH I253
J 0
(3350 2475);
DISPLAY 0.872340 (3350 2475);
PAINT AQUA (3350 2475);
DISPLAY INVISIBLE (3350 2475);
FORCEPROP 2 LAST ROOM IO_SLOT
J 1
(3050 2550);
DISPLAY 0.744681 (3050 2550);
DISPLAY INVISIBLE (3050 2550);
FORCEADD OFFPAGE..2
(2875 4100);
FORCEPROP 2 LAST $XR2 215 
J 0
(3304 4100);
DISPLAY 0.638298 (3304 4100);
PAINT MONO (3304 4100);
FORCEPROP 2 LAST $XR1 191 
J 0
(3184 4100);
DISPLAY 0.638298 (3184 4100);
PAINT MONO (3184 4100);
FORCEPROP 2 LAST $XR0 183 
J 0
(3064 4100);
DISPLAY 0.638298 (3064 4100);
PAINT MONO (3064 4100);
FORCEPROP 2 LAST CDS_LIB standard
J 0
(2875 4100);
DISPLAY INVISIBLE (2875 4100);
FORCEPROP 1 LAST OFFPAGE TRUE
J 0
(3200 3975);
DISPLAY 0.872340 (3200 3975);
PAINT GREEN (3200 3975);
DISPLAY INVISIBLE (3200 3975);
FORCEPROP 1 LAST COMMENT_BODY TRUE
J 0
(2830 4005);
DISPLAY 0.872340 (2830 4005);
PAINT GREEN (2830 4005);
DISPLAY INVISIBLE (2830 4005);
FORCEPROP 2 LAST PATH I254
J 0
(3225 4150);
DISPLAY 1.021277 (3225 4150);
DISPLAY INVISIBLE (3225 4150);
FORCEADD OFFPAGE..4
(2875 4200);
FORCEPROP 2 LAST $XR0 214 
J 0
(3061 4200);
DISPLAY 0.638298 (3061 4200);
PAINT MONO (3061 4200);
FORCEPROP 2 LAST CDS_LIB standard
J 0
(2875 4200);
PAINT MONO (2875 4200);
DISPLAY INVISIBLE (2875 4200);
FORCEPROP 1 LAST OFFPAGE TRUE
J 0
(3200 4075);
DISPLAY 0.872340 (3200 4075);
PAINT GREEN (3200 4075);
DISPLAY INVISIBLE (3200 4075);
FORCEPROP 1 LAST COMMENT_BODY TRUE
J 0
(2850 4100);
DISPLAY 0.872340 (2850 4100);
PAINT GREEN (2850 4100);
DISPLAY INVISIBLE (2850 4100);
FORCEPROP 2 LAST PATH I255
J 0
(3225 4250);
DISPLAY 1.021277 (3225 4250);
DISPLAY INVISIBLE (3225 4250);
FORCEADD OFFPAGE..2
(2900 3775);
FORCEPROP 2 LAST $XR0 181 
J 0
(3089 3775);
DISPLAY 0.638298 (3089 3775);
PAINT MONO (3089 3775);
FORCEPROP 2 LAST CDS_LIB standard
J 0
(2900 3775);
DISPLAY INVISIBLE (2900 3775);
FORCEPROP 1 LAST OFFPAGE TRUE
J 0
(3225 3650);
DISPLAY 0.872340 (3225 3650);
PAINT GREEN (3225 3650);
DISPLAY INVISIBLE (3225 3650);
FORCEPROP 1 LAST COMMENT_BODY TRUE
J 0
(2855 3680);
DISPLAY 0.872340 (2855 3680);
PAINT GREEN (2855 3680);
DISPLAY INVISIBLE (2855 3680);
FORCEPROP 2 LAST PATH I256
J 0
(3100 3825);
DISPLAY 1.021277 (3100 3825);
DISPLAY INVISIBLE (3100 3825);
FORCEADD OFFPAGE..2
(2900 3825);
FORCEPROP 2 LAST $XR0 181 
J 0
(3089 3825);
DISPLAY 0.638298 (3089 3825);
PAINT MONO (3089 3825);
FORCEPROP 2 LAST CDS_LIB standard
J 0
(2900 3825);
DISPLAY INVISIBLE (2900 3825);
FORCEPROP 1 LAST OFFPAGE TRUE
J 0
(3225 3700);
DISPLAY 0.872340 (3225 3700);
PAINT GREEN (3225 3700);
DISPLAY INVISIBLE (3225 3700);
FORCEPROP 1 LAST COMMENT_BODY TRUE
J 0
(2855 3730);
DISPLAY 0.872340 (2855 3730);
PAINT GREEN (2855 3730);
DISPLAY INVISIBLE (2855 3730);
FORCEPROP 2 LAST PATH I257
J 0
(3100 3875);
DISPLAY 1.021277 (3100 3875);
DISPLAY INVISIBLE (3100 3875);
FORCEADD Q_CAP..1
(3000 2825);
FORCEPROP 1 LAST PART_NUMBER CH4104K1B00
J 0
(3050 2675);
DISPLAY 0.808511 (3050 2675);
DISPLAY INVISIBLE (3050 2675);
FORCEPROP 1 LAST VALUE 0.1UF
J 0
(3050 2875);
DISPLAY 0.638298 (3050 2875);
FORCEPROP 1 LAST MATERIAL X7R
J 0
(3050 2725);
DISPLAY 0.638298 (3050 2725);
FORCEPROP 1 LAST TOLERANCE 10%
J 0
(3050 2775);
DISPLAY 0.638298 (3050 2775);
FORCEPROP 1 LAST VOLTAGE 25V
J 0
(3050 2825);
DISPLAY 0.638298 (3050 2825);
FORCEPROP 1 LAST PACK_TYPE 0402
J 0
(3050 2675);
DISPLAY 0.638298 (3050 2675);
FORCEPROP 1 LAST $LOCATION C1278
J 0
(3050 2925);
DISPLAY 0.787234 (3050 2925);
FORCEPROP 1 LASTPIN (3000 2925) $PN 1
J 0
(3010 2905);
DISPLAY 0.787234 (3010 2905);
FORCEPROP 1 LASTPIN (3000 2725) $PN 2
J 0
(3010 2705);
DISPLAY 0.787234 (3010 2705);
FORCEPROP 2 LAST CDS_LIB pure_quanta
J 0
(3000 2825);
PAINT MONO (3000 2825);
DISPLAY INVISIBLE (3000 2825);
FORCEPROP 1 LAST PATH I258
J 0
(3050 2975);
DISPLAY 0.978723 (3050 2975);
PAINT WHITE (3050 2975);
DISPLAY INVISIBLE (3050 2975);
FORCEPROP 2 LAST CDS_LOCATION C1278
J 0
(3050 3025);
DISPLAY 1.021277 (3050 3025);
DISPLAY INVISIBLE (3050 3025);
FORCEPROP 2 LAST $SEC 1
J 0
(3050 3025);
DISPLAY 0.680851 (3050 3025);
PAINT MONO (3050 3025);
DISPLAY INVISIBLE (3050 3025);
FORCEPROP 2 LAST CDS_SEC 1
J 0
(3050 3025);
DISPLAY 1.021277 (3050 3025);
DISPLAY INVISIBLE (3050 3025);
FORCEADD UNIVERSAL_POWER..1
(2325 3175);
FORCEPROP 3 LASTPIN (2325 3125) SIG_NAME P12V_E1S_0\g
J 0
(2335 3135);
DISPLAY 0.659574 (2335 3135);
PAINT MONO (2335 3135);
DISPLAY INVISIBLE (2335 3135);
FORCEPROP 1 LAST HDL_POWER P12V_E1S_0
J 1
(2325 3225);
DISPLAY 0.872340 (2325 3225);
PAINT GREEN (2325 3225);
FORCEPROP 2 LAST CDS_LIB logical_power
J 0
(2325 3175);
PAINT MONO (2325 3175);
DISPLAY INVISIBLE (2325 3175);
FORCEPROP 1 LAST PATH I259
J 0
(2375 3200);
DISPLAY 0.872340 (2375 3200);
PAINT AQUA (2375 3200);
DISPLAY INVISIBLE (2375 3200);
FORCEADD Q_CAP..1
(2325 2825);
FORCEPROP 1 LAST PART_NUMBER CH6223MEA01
J 0
(2375 2625);
DISPLAY 0.808511 (2375 2625);
DISPLAY INVISIBLE (2375 2625);
FORCEPROP 1 LAST MATERIAL X6S
J 0
(2375 2725);
DISPLAY 0.638298 (2375 2725);
FORCEPROP 1 LAST VOLTAGE 16V
J 0
(2375 2825);
DISPLAY 0.638298 (2375 2825);
FORCEPROP 1 LAST PACK_TYPE C0805
J 0
(2375 2675);
DISPLAY 0.638298 (2375 2675);
FORCEPROP 1 LAST TOLERANCE 20%
J 0
(2375 2775);
DISPLAY 0.638298 (2375 2775);
FORCEPROP 1 LAST VALUE 22UF
J 0
(2375 2875);
DISPLAY 0.638298 (2375 2875);
FORCEPROP 1 LAST $LOCATION C1276
J 0
(2375 2925);
DISPLAY 0.787234 (2375 2925);
FORCEPROP 1 LASTPIN (2325 2925) $PN 1
J 0
(2335 2905);
DISPLAY 0.787234 (2335 2905);
FORCEPROP 1 LASTPIN (2325 2725) $PN 2
J 0
(2335 2705);
DISPLAY 0.787234 (2335 2705);
FORCEPROP 2 LAST CDS_LIB pure_quanta
J 0
(2325 2825);
PAINT MONO (2325 2825);
DISPLAY INVISIBLE (2325 2825);
FORCEPROP 1 LAST PATH I260
J 0
(2375 2975);
DISPLAY 0.978723 (2375 2975);
PAINT WHITE (2375 2975);
DISPLAY INVISIBLE (2375 2975);
FORCEPROP 2 LAST CDS_LOCATION C1276
J 0
(2375 3025);
DISPLAY 1.021277 (2375 3025);
DISPLAY INVISIBLE (2375 3025);
FORCEPROP 2 LAST $SEC 1
J 0
(2375 3025);
DISPLAY 0.680851 (2375 3025);
PAINT MONO (2375 3025);
DISPLAY INVISIBLE (2375 3025);
FORCEPROP 2 LAST CDS_SEC 1
J 0
(2375 3025);
DISPLAY 1.021277 (2375 3025);
DISPLAY INVISIBLE (2375 3025);
FORCEADD UNIVERSAL_POWER..1
(-350 5175);
FORCEPROP 3 LASTPIN (-350 5125) SIG_NAME P12V_E1S_0\g
J 0
(-340 5135);
DISPLAY 0.659574 (-340 5135);
PAINT MONO (-340 5135);
DISPLAY INVISIBLE (-340 5135);
FORCEPROP 1 LAST HDL_POWER P12V_E1S_0
J 1
(-350 5225);
DISPLAY 0.872340 (-350 5225);
PAINT GREEN (-350 5225);
FORCEPROP 2 LAST CDS_LIB logical_power
J 0
(-350 5175);
DISPLAY INVISIBLE (-350 5175);
FORCEPROP 1 LAST PATH I261
J 0
(-300 5200);
DISPLAY 0.872340 (-300 5200);
PAINT AQUA (-300 5200);
DISPLAY INVISIBLE (-300 5200);
FORCEADD UNIVERSAL_POWER..1
(-650 5000);
FORCEPROP 3 LASTPIN (-650 4950) SIG_NAME P3V3_E1S_0\g
J 0
(-640 4960);
DISPLAY 0.659574 (-640 4960);
PAINT MONO (-640 4960);
DISPLAY INVISIBLE (-640 4960);
FORCEPROP 1 LAST HDL_POWER P3V3_E1S_0
J 1
(-650 5050);
DISPLAY 0.872340 (-650 5050);
PAINT GREEN (-650 5050);
FORCEPROP 2 LAST CDS_LIB logical_power
J 0
(-650 5000);
DISPLAY INVISIBLE (-650 5000);
FORCEPROP 1 LAST PATH I262
J 0
(-600 5025);
DISPLAY 0.872340 (-600 5025);
PAINT AQUA (-600 5025);
DISPLAY INVISIBLE (-600 5025);
FORCEADD UNIVERSAL_POWER..1
(-1925 4775);
FORCEPROP 3 LASTPIN (-1925 4725) SIG_NAME P3V3_E1S_0\g
J 0
(-1915 4735);
DISPLAY 0.659574 (-1915 4735);
PAINT MONO (-1915 4735);
DISPLAY INVISIBLE (-1915 4735);
FORCEPROP 1 LAST HDL_POWER P3V3_E1S_0
J 1
(-1925 4825);
DISPLAY 0.872340 (-1925 4825);
PAINT GREEN (-1925 4825);
FORCEPROP 2 LAST CDS_LIB logical_power
J 0
(-1925 4775);
DISPLAY INVISIBLE (-1925 4775);
FORCEPROP 1 LAST PATH I263
J 0
(-1875 4800);
DISPLAY 0.872340 (-1875 4800);
PAINT AQUA (-1875 4800);
DISPLAY INVISIBLE (-1875 4800);
FORCEADD Q_RES..2
(-1925 4525);
FORCEPROP 1 LAST PART_NUMBER CS31002FB08
J 0
(-1885 4400);
DISPLAY 0.723404 (-1885 4400);
PAINT WHITE (-1885 4400);
DISPLAY INVISIBLE (-1885 4400);
FORCEPROP 1 LAST PACK_TYPE 0402LF
J 0
(-1875 4375);
DISPLAY 0.723404 (-1875 4375);
PAINT SKYBLUE (-1875 4375);
FORCEPROP 1 LAST MATERIAL CHIP
J 0
(-1885 4450);
DISPLAY 0.723404 (-1885 4450);
PAINT SKYBLUE (-1885 4450);
FORCEPROP 1 LAST VALUE 10K
J 0
(-1880 4600);
DISPLAY 0.723404 (-1880 4600);
PAINT SKYBLUE (-1880 4600);
FORCEPROP 1 LAST TOLERANCE 1%
J 0
(-1880 4550);
DISPLAY 0.723404 (-1880 4550);
PAINT SKYBLUE (-1880 4550);
FORCEPROP 1 LAST WATTAGE 1/16W
J 0
(-1885 4500);
DISPLAY 0.723404 (-1885 4500);
PAINT SKYBLUE (-1885 4500);
FORCEPROP 1 LAST LOCATION R2317
J 0
(-1880 4650);
DISPLAY 0.723404 (-1880 4650);
PAINT AQUA (-1880 4650);
FORCEPROP 1 LASTPIN (-1925 4625) $PN 1
J 0
(-1920 4587);
DISPLAY 0.787234 (-1920 4587);
PAINT MONO (-1920 4587);
FORCEPROP 1 LASTPIN (-1925 4425) $PN 2
J 0
(-1920 4435);
DISPLAY 0.787234 (-1920 4435);
PAINT MONO (-1920 4435);
FORCEPROP 2 LAST CDS_LIB pure_quanta
J 0
(-1925 4525);
DISPLAY INVISIBLE (-1925 4525);
FORCEPROP 1 LAST PATH I264
J 0
(-1875 4700);
DISPLAY 0.978723 (-1875 4700);
PAINT WHITE (-1875 4700);
DISPLAY INVISIBLE (-1875 4700);
FORCEPROP 0 LAST $SEC 1
J 0
(-1875 4700);
DISPLAY 0.680851 (-1875 4700);
PAINT MONO (-1875 4700);
DISPLAY INVISIBLE (-1875 4700);
FORCEPROP 0 LAST CDS_SEC 1
J 0
(-1875 4700);
DISPLAY 1.021277 (-1875 4700);
DISPLAY INVISIBLE (-1875 4700);
FORCEADD TAP..1
(1825 3650);
FORCEPROP 3 LASTPIN (1775 3650) SIG_NAME P3E_PCH_E1S_RX_DN<1>
J 0
(1785 3660);
DISPLAY 0.659574 (1785 3660);
PAINT MONO (1785 3660);
DISPLAY INVISIBLE (1785 3660);
FORCEPROP 1 LASTPIN (1775 3650) BN 1
J 0
(1763 3658);
DISPLAY 0.680851 (1763 3658);
PAINT GREEN (1763 3658);
FORCEPROP 2 LAST CDS_LIB standard
J 0
(1825 3650);
PAINT MONO (1825 3650);
DISPLAY INVISIBLE (1825 3650);
FORCEPROP 1 LAST BODY_TYPE PLUMBING
J 0
(1825 3700);
DISPLAY 0.872340 (1825 3700);
PAINT GREEN (1825 3700);
DISPLAY INVISIBLE (1825 3700);
FORCEPROP 1 LAST HDL_TAP TRUE
J 0
(2150 3525);
DISPLAY 0.872340 (2150 3525);
PAINT GREEN (2150 3525);
DISPLAY INVISIBLE (2150 3525);
FORCEPROP 1 LAST PATH I267
J 0
(1823 3650);
DISPLAY 0.872340 (1823 3650);
PAINT GREEN (1823 3650);
DISPLAY INVISIBLE (1823 3650);
FORCEADD TAP..1
(1825 3500);
FORCEPROP 3 LASTPIN (1775 3500) SIG_NAME P3E_PCH_E1S_RX_DN<2>
J 0
(1785 3510);
DISPLAY 0.659574 (1785 3510);
PAINT MONO (1785 3510);
DISPLAY INVISIBLE (1785 3510);
FORCEPROP 1 LASTPIN (1775 3500) BN 2
J 0
(1763 3508);
DISPLAY 0.680851 (1763 3508);
PAINT GREEN (1763 3508);
FORCEPROP 2 LAST CDS_LIB standard
J 0
(1825 3500);
PAINT MONO (1825 3500);
DISPLAY INVISIBLE (1825 3500);
FORCEPROP 1 LAST BODY_TYPE PLUMBING
J 0
(1825 3550);
DISPLAY 0.872340 (1825 3550);
PAINT GREEN (1825 3550);
DISPLAY INVISIBLE (1825 3550);
FORCEPROP 1 LAST HDL_TAP TRUE
J 0
(2150 3375);
DISPLAY 0.872340 (2150 3375);
PAINT GREEN (2150 3375);
DISPLAY INVISIBLE (2150 3375);
FORCEPROP 1 LAST PATH I268
J 0
(1823 3500);
DISPLAY 0.872340 (1823 3500);
PAINT GREEN (1823 3500);
DISPLAY INVISIBLE (1823 3500);
FORCEADD TAP..1
(1675 3600);
FORCEPROP 3 LASTPIN (1625 3600) SIG_NAME P3E_PCH_E1S_RX_DP<1>
J 0
(1635 3610);
DISPLAY 0.659574 (1635 3610);
PAINT MONO (1635 3610);
DISPLAY INVISIBLE (1635 3610);
FORCEPROP 1 LASTPIN (1625 3600) BN 1
J 0
(1613 3608);
DISPLAY 0.680851 (1613 3608);
PAINT GREEN (1613 3608);
FORCEPROP 2 LAST CDS_LIB standard
J 0
(1675 3600);
PAINT MONO (1675 3600);
DISPLAY INVISIBLE (1675 3600);
FORCEPROP 1 LAST BODY_TYPE PLUMBING
J 0
(1675 3650);
DISPLAY 0.872340 (1675 3650);
PAINT GREEN (1675 3650);
DISPLAY INVISIBLE (1675 3650);
FORCEPROP 1 LAST HDL_TAP TRUE
J 0
(2000 3475);
DISPLAY 0.872340 (2000 3475);
PAINT GREEN (2000 3475);
DISPLAY INVISIBLE (2000 3475);
FORCEPROP 1 LAST PATH I269
J 0
(1673 3600);
DISPLAY 0.872340 (1673 3600);
PAINT GREEN (1673 3600);
DISPLAY INVISIBLE (1673 3600);
FORCEADD TAP..1
(1675 3450);
FORCEPROP 3 LASTPIN (1625 3450) SIG_NAME P3E_PCH_E1S_RX_DP<2>
J 0
(1635 3460);
DISPLAY 0.659574 (1635 3460);
PAINT MONO (1635 3460);
DISPLAY INVISIBLE (1635 3460);
FORCEPROP 1 LASTPIN (1625 3450) BN 2
J 0
(1613 3458);
DISPLAY 0.680851 (1613 3458);
PAINT GREEN (1613 3458);
FORCEPROP 2 LAST CDS_LIB standard
J 0
(1675 3450);
PAINT MONO (1675 3450);
DISPLAY INVISIBLE (1675 3450);
FORCEPROP 1 LAST BODY_TYPE PLUMBING
J 0
(1675 3500);
DISPLAY 0.872340 (1675 3500);
PAINT GREEN (1675 3500);
DISPLAY INVISIBLE (1675 3500);
FORCEPROP 1 LAST HDL_TAP TRUE
J 0
(2000 3325);
DISPLAY 0.872340 (2000 3325);
PAINT GREEN (2000 3325);
DISPLAY INVISIBLE (2000 3325);
FORCEPROP 1 LAST PATH I270
J 0
(1673 3450);
DISPLAY 0.872340 (1673 3450);
PAINT GREEN (1673 3450);
DISPLAY INVISIBLE (1673 3450);
FORCEADD TAP..1
(1825 3350);
FORCEPROP 3 LASTPIN (1775 3350) SIG_NAME P3E_PCH_E1S_RX_DN<3>
J 0
(1785 3360);
DISPLAY 0.659574 (1785 3360);
PAINT MONO (1785 3360);
DISPLAY INVISIBLE (1785 3360);
FORCEPROP 1 LASTPIN (1775 3350) BN 3
J 0
(1763 3358);
DISPLAY 0.680851 (1763 3358);
PAINT GREEN (1763 3358);
FORCEPROP 2 LAST CDS_LIB standard
J 0
(1825 3350);
PAINT MONO (1825 3350);
DISPLAY INVISIBLE (1825 3350);
FORCEPROP 1 LAST BODY_TYPE PLUMBING
J 0
(1825 3400);
DISPLAY 0.872340 (1825 3400);
PAINT GREEN (1825 3400);
DISPLAY INVISIBLE (1825 3400);
FORCEPROP 1 LAST HDL_TAP TRUE
J 0
(2150 3225);
DISPLAY 0.872340 (2150 3225);
PAINT GREEN (2150 3225);
DISPLAY INVISIBLE (2150 3225);
FORCEPROP 1 LAST PATH I271
J 0
(1823 3350);
DISPLAY 0.872340 (1823 3350);
PAINT GREEN (1823 3350);
DISPLAY INVISIBLE (1823 3350);
FORCEADD TAP..1
(1675 3300);
FORCEPROP 3 LASTPIN (1625 3300) SIG_NAME P3E_PCH_E1S_RX_DP<3>
J 0
(1635 3310);
DISPLAY 0.659574 (1635 3310);
PAINT MONO (1635 3310);
DISPLAY INVISIBLE (1635 3310);
FORCEPROP 1 LASTPIN (1625 3300) BN 3
J 0
(1613 3308);
DISPLAY 0.680851 (1613 3308);
PAINT GREEN (1613 3308);
FORCEPROP 2 LAST CDS_LIB standard
J 0
(1675 3300);
PAINT MONO (1675 3300);
DISPLAY INVISIBLE (1675 3300);
FORCEPROP 1 LAST BODY_TYPE PLUMBING
J 0
(1675 3350);
DISPLAY 0.872340 (1675 3350);
PAINT GREEN (1675 3350);
DISPLAY INVISIBLE (1675 3350);
FORCEPROP 1 LAST HDL_TAP TRUE
J 0
(2000 3175);
DISPLAY 0.872340 (2000 3175);
PAINT GREEN (2000 3175);
DISPLAY INVISIBLE (2000 3175);
FORCEPROP 1 LAST PATH I272
J 0
(1673 3300);
DISPLAY 0.872340 (1673 3300);
PAINT GREEN (1673 3300);
DISPLAY INVISIBLE (1673 3300);
FORCEADD UNIVERSAL_GND..1
(1400 2950);
FORCEPROP 3 LASTPIN (1400 3000) SIG_NAME GND\g
J 0
(1410 3010);
DISPLAY 0.659574 (1410 3010);
PAINT MONO (1410 3010);
DISPLAY INVISIBLE (1410 3010);
FORCEPROP 2 LAST CDS_LIB logical_power
J 0
(1400 2950);
DISPLAY INVISIBLE (1400 2950);
FORCEPROP 1 LAST HDL_POWER GND
J 1
(1425 2875);
DISPLAY 0.872340 (1425 2875);
PAINT GREEN (1425 2875);
DISPLAY INVISIBLE (1425 2875);
FORCEPROP 1 LAST PATH I273
J 0
(1475 2950);
DISPLAY 0.872340 (1475 2950);
PAINT AQUA (1475 2950);
DISPLAY INVISIBLE (1475 2950);
FORCEPROP 2 LAST ROOM IO_SLOT
J 1
(1175 3025);
DISPLAY 0.744681 (1175 3025);
DISPLAY INVISIBLE (1175 3025);
FORCEADD UNIVERSAL_GND..1
(-400 2950);
FORCEPROP 3 LASTPIN (-400 3000) SIG_NAME GND\g
J 0
(-390 3010);
DISPLAY 0.659574 (-390 3010);
PAINT MONO (-390 3010);
DISPLAY INVISIBLE (-390 3010);
FORCEPROP 2 LAST CDS_LIB logical_power
J 0
(-400 2950);
DISPLAY INVISIBLE (-400 2950);
FORCEPROP 1 LAST HDL_POWER GND
J 1
(-375 2875);
DISPLAY 0.872340 (-375 2875);
PAINT GREEN (-375 2875);
DISPLAY INVISIBLE (-375 2875);
FORCEPROP 1 LAST PATH I275
J 0
(-325 2950);
DISPLAY 0.872340 (-325 2950);
PAINT AQUA (-325 2950);
DISPLAY INVISIBLE (-325 2950);
FORCEPROP 2 LAST ROOM IO_SLOT
J 1
(-625 3025);
DISPLAY 0.744681 (-625 3025);
DISPLAY INVISIBLE (-625 3025);
FORCEADD TAP..1
R 2
(-625 3450);
FORCEPROP 3 LASTPIN (-575 3450) SIG_NAME P3E_PCH_E1S_TX_C_DP<2>
J 0
(-565 3460);
DISPLAY 0.659574 (-565 3460);
PAINT MONO (-565 3460);
DISPLAY INVISIBLE (-565 3460);
FORCEPROP 1 LASTPIN (-575 3450) BN 2
J 2
(-563 3458);
DISPLAY 0.680851 (-563 3458);
PAINT GREEN (-563 3458);
FORCEPROP 2 LAST CDS_LIB standard
J 0
(-625 3450);
PAINT MONO (-625 3450);
DISPLAY INVISIBLE (-625 3450);
FORCEPROP 1 LAST BODY_TYPE PLUMBING
J 2
(-625 3500);
DISPLAY 0.872340 (-625 3500);
PAINT GREEN (-625 3500);
DISPLAY INVISIBLE (-625 3500);
FORCEPROP 1 LAST HDL_TAP TRUE
J 2
(-950 3325);
DISPLAY 0.872340 (-950 3325);
PAINT GREEN (-950 3325);
DISPLAY INVISIBLE (-950 3325);
FORCEPROP 1 LAST PATH I278
J 2
(-623 3450);
DISPLAY 0.872340 (-623 3450);
PAINT GREEN (-623 3450);
DISPLAY INVISIBLE (-623 3450);
FORCEADD TAP..1
R 2
(-625 3300);
FORCEPROP 3 LASTPIN (-575 3300) SIG_NAME P3E_PCH_E1S_TX_C_DP<3>
J 0
(-565 3310);
DISPLAY 0.659574 (-565 3310);
PAINT MONO (-565 3310);
DISPLAY INVISIBLE (-565 3310);
FORCEPROP 1 LASTPIN (-575 3300) BN 3
J 2
(-563 3308);
DISPLAY 0.680851 (-563 3308);
PAINT GREEN (-563 3308);
FORCEPROP 2 LAST CDS_LIB standard
J 0
(-625 3300);
PAINT MONO (-625 3300);
DISPLAY INVISIBLE (-625 3300);
FORCEPROP 1 LAST BODY_TYPE PLUMBING
J 2
(-625 3350);
DISPLAY 0.872340 (-625 3350);
PAINT GREEN (-625 3350);
DISPLAY INVISIBLE (-625 3350);
FORCEPROP 1 LAST HDL_TAP TRUE
J 2
(-950 3175);
DISPLAY 0.872340 (-950 3175);
PAINT GREEN (-950 3175);
DISPLAY INVISIBLE (-950 3175);
FORCEPROP 1 LAST PATH I280
J 2
(-623 3300);
DISPLAY 0.872340 (-623 3300);
PAINT GREEN (-623 3300);
DISPLAY INVISIBLE (-623 3300);
FORCEADD TAP..1
R 2
(-775 3500);
FORCEPROP 3 LASTPIN (-725 3500) SIG_NAME P3E_PCH_E1S_TX_C_DN<2>
J 0
(-715 3510);
DISPLAY 0.659574 (-715 3510);
PAINT MONO (-715 3510);
DISPLAY INVISIBLE (-715 3510);
FORCEPROP 1 LASTPIN (-725 3500) BN 2
J 2
(-713 3508);
DISPLAY 0.680851 (-713 3508);
PAINT GREEN (-713 3508);
FORCEPROP 2 LAST CDS_LIB standard
J 0
(-775 3500);
PAINT MONO (-775 3500);
DISPLAY INVISIBLE (-775 3500);
FORCEPROP 1 LAST BODY_TYPE PLUMBING
J 2
(-775 3550);
DISPLAY 0.872340 (-775 3550);
PAINT GREEN (-775 3550);
DISPLAY INVISIBLE (-775 3550);
FORCEPROP 1 LAST HDL_TAP TRUE
J 2
(-1100 3375);
DISPLAY 0.872340 (-1100 3375);
PAINT GREEN (-1100 3375);
DISPLAY INVISIBLE (-1100 3375);
FORCEPROP 1 LAST PATH I281
J 2
(-773 3500);
DISPLAY 0.872340 (-773 3500);
PAINT GREEN (-773 3500);
DISPLAY INVISIBLE (-773 3500);
FORCEADD TAP..1
R 2
(-775 3350);
FORCEPROP 3 LASTPIN (-725 3350) SIG_NAME P3E_PCH_E1S_TX_C_DN<3>
J 0
(-715 3360);
DISPLAY 0.659574 (-715 3360);
PAINT MONO (-715 3360);
DISPLAY INVISIBLE (-715 3360);
FORCEPROP 1 LASTPIN (-725 3350) BN 3
J 2
(-713 3358);
DISPLAY 0.680851 (-713 3358);
PAINT GREEN (-713 3358);
FORCEPROP 2 LAST CDS_LIB standard
J 0
(-775 3350);
PAINT MONO (-775 3350);
DISPLAY INVISIBLE (-775 3350);
FORCEPROP 1 LAST BODY_TYPE PLUMBING
J 2
(-775 3400);
DISPLAY 0.872340 (-775 3400);
PAINT GREEN (-775 3400);
DISPLAY INVISIBLE (-775 3400);
FORCEPROP 1 LAST HDL_TAP TRUE
J 2
(-1100 3225);
DISPLAY 0.872340 (-1100 3225);
PAINT GREEN (-1100 3225);
DISPLAY INVISIBLE (-1100 3225);
FORCEPROP 1 LAST PATH I283
J 2
(-773 3350);
DISPLAY 0.872340 (-773 3350);
PAINT GREEN (-773 3350);
DISPLAY INVISIBLE (-773 3350);
FORCEADD OFFPAGE..1
(-1675 4100);
FORCEPROP 2 LAST $XR0 191 
J 0
(-1957 4100);
DISPLAY 0.638298 (-1957 4100);
PAINT MONO (-1957 4100);
FORCEPROP 2 LAST CDS_LIB standard
J 0
(-1675 4100);
PAINT MONO (-1675 4100);
DISPLAY INVISIBLE (-1675 4100);
FORCEPROP 1 LAST OFFPAGE TRUE
J 0
(-1350 3975);
DISPLAY 0.872340 (-1350 3975);
PAINT GREEN (-1350 3975);
DISPLAY INVISIBLE (-1350 3975);
FORCEPROP 1 LAST COMMENT_BODY TRUE
J 0
(-1550 4000);
DISPLAY 0.872340 (-1550 4000);
PAINT GREEN (-1550 4000);
DISPLAY INVISIBLE (-1550 4000);
FORCEPROP 2 LAST PATH I285
J 0
(-1950 4150);
DISPLAY 1.021277 (-1950 4150);
DISPLAY INVISIBLE (-1950 4150);
FORCEADD OFFPAGE..1
(-1675 3950);
FORCEPROP 2 LAST $XR0 179 
J 0
(-1957 3950);
DISPLAY 0.638298 (-1957 3950);
PAINT MONO (-1957 3950);
FORCEPROP 2 LAST CDS_LIB standard
J 0
(-1675 3950);
PAINT MONO (-1675 3950);
DISPLAY INVISIBLE (-1675 3950);
FORCEPROP 1 LAST OFFPAGE TRUE
J 0
(-1350 3825);
DISPLAY 0.872340 (-1350 3825);
PAINT GREEN (-1350 3825);
DISPLAY INVISIBLE (-1350 3825);
FORCEPROP 1 LAST COMMENT_BODY TRUE
J 0
(-1550 3850);
DISPLAY 0.872340 (-1550 3850);
PAINT GREEN (-1550 3850);
DISPLAY INVISIBLE (-1550 3850);
FORCEPROP 2 LAST PATH I286
J 0
(-1950 4000);
DISPLAY 1.021277 (-1950 4000);
DISPLAY INVISIBLE (-1950 4000);
FORCEADD OFFPAGE..1
(-1675 3900);
FORCEPROP 2 LAST $XR0 179 
J 0
(-1957 3900);
DISPLAY 0.638298 (-1957 3900);
PAINT MONO (-1957 3900);
FORCEPROP 2 LAST CDS_LIB standard
J 0
(-1675 3900);
PAINT MONO (-1675 3900);
DISPLAY INVISIBLE (-1675 3900);
FORCEPROP 1 LAST OFFPAGE TRUE
J 0
(-1350 3775);
DISPLAY 0.872340 (-1350 3775);
PAINT GREEN (-1350 3775);
DISPLAY INVISIBLE (-1350 3775);
FORCEPROP 1 LAST COMMENT_BODY TRUE
J 0
(-1550 3800);
DISPLAY 0.872340 (-1550 3800);
PAINT GREEN (-1550 3800);
DISPLAY INVISIBLE (-1550 3800);
FORCEPROP 2 LAST PATH I287
J 0
(-1950 3950);
DISPLAY 1.021277 (-1950 3950);
DISPLAY INVISIBLE (-1950 3950);
FORCEADD OFFPAGE..1
(-1675 3775);
FORCEPROP 2 LAST $XR0 181 
J 0
(-1957 3775);
DISPLAY 0.638298 (-1957 3775);
PAINT MONO (-1957 3775);
FORCEPROP 2 LAST CDS_LIB standard
J 0
(-1675 3775);
DISPLAY INVISIBLE (-1675 3775);
FORCEPROP 1 LAST OFFPAGE TRUE
J 0
(-1350 3650);
DISPLAY 0.872340 (-1350 3650);
PAINT GREEN (-1350 3650);
DISPLAY INVISIBLE (-1350 3650);
FORCEPROP 1 LAST COMMENT_BODY TRUE
J 0
(-1550 3675);
DISPLAY 0.872340 (-1550 3675);
PAINT GREEN (-1550 3675);
DISPLAY INVISIBLE (-1550 3675);
FORCEPROP 2 LAST PATH I288
J 0
(-1950 3825);
DISPLAY 1.021277 (-1950 3825);
DISPLAY INVISIBLE (-1950 3825);
FORCEADD OFFPAGE..1
(-1675 3825);
FORCEPROP 2 LAST $XR0 181 
J 0
(-1957 3825);
DISPLAY 0.638298 (-1957 3825);
PAINT MONO (-1957 3825);
FORCEPROP 2 LAST CDS_LIB standard
J 0
(-1675 3825);
DISPLAY INVISIBLE (-1675 3825);
FORCEPROP 1 LAST OFFPAGE TRUE
J 0
(-1350 3700);
DISPLAY 0.872340 (-1350 3700);
PAINT GREEN (-1350 3700);
DISPLAY INVISIBLE (-1350 3700);
FORCEPROP 1 LAST COMMENT_BODY TRUE
J 0
(-1550 3725);
DISPLAY 0.872340 (-1550 3725);
PAINT GREEN (-1550 3725);
DISPLAY INVISIBLE (-1550 3725);
FORCEPROP 2 LAST PATH I289
J 0
(-1950 3875);
DISPLAY 1.021277 (-1950 3875);
DISPLAY INVISIBLE (-1950 3875);
FORCEADD UNIVERSAL_POWER..1
(-3475 3700);
FORCEPROP 3 LASTPIN (-3475 3650) SIG_NAME P3V3_AUX\g
J 0
(-3465 3660);
DISPLAY 0.659574 (-3465 3660);
PAINT MONO (-3465 3660);
DISPLAY INVISIBLE (-3465 3660);
FORCEPROP 1 LAST HDL_POWER P3V3_AUX
J 1
(-3475 3750);
DISPLAY 0.872340 (-3475 3750);
PAINT GREEN (-3475 3750);
FORCEPROP 2 LAST CDS_LIB logical_power
J 0
(-3475 3700);
DISPLAY INVISIBLE (-3475 3700);
FORCEPROP 1 LAST PATH I290
J 0
(-3425 3725);
DISPLAY 0.872340 (-3425 3725);
PAINT AQUA (-3425 3725);
DISPLAY INVISIBLE (-3425 3725);
FORCEADD Q_RES..2
(-3475 3450);
FORCEPROP 1 LAST PART_NUMBER CS31002FB08
J 0
(-3435 3325);
DISPLAY 0.723404 (-3435 3325);
PAINT WHITE (-3435 3325);
DISPLAY INVISIBLE (-3435 3325);
FORCEPROP 1 LAST VALUE 10K
J 0
(-3430 3525);
DISPLAY 0.723404 (-3430 3525);
PAINT SKYBLUE (-3430 3525);
FORCEPROP 1 LAST PACK_TYPE 0402LF
J 0
(-3425 3325);
DISPLAY 0.723404 (-3425 3325);
PAINT SKYBLUE (-3425 3325);
FORCEPROP 1 LAST MATERIAL CHIP
J 0
(-3435 3375);
DISPLAY 0.723404 (-3435 3375);
PAINT SKYBLUE (-3435 3375);
FORCEPROP 1 LAST WATTAGE 1/16W
J 0
(-3435 3425);
DISPLAY 0.723404 (-3435 3425);
PAINT SKYBLUE (-3435 3425);
FORCEPROP 1 LAST TOLERANCE 1%
J 0
(-3430 3475);
DISPLAY 0.723404 (-3430 3475);
PAINT SKYBLUE (-3430 3475);
FORCEPROP 1 LAST $LOCATION R3771
J 0
(-3430 3575);
DISPLAY 0.723404 (-3430 3575);
PAINT AQUA (-3430 3575);
FORCEPROP 1 LASTPIN (-3475 3550) $PN 1
J 0
(-3470 3512);
DISPLAY 0.787234 (-3470 3512);
PAINT MONO (-3470 3512);
FORCEPROP 1 LASTPIN (-3475 3350) $PN 2
J 0
(-3470 3360);
DISPLAY 0.787234 (-3470 3360);
PAINT MONO (-3470 3360);
FORCEPROP 2 LAST CDS_LIB pure_quanta
J 0
(-3475 3450);
DISPLAY INVISIBLE (-3475 3450);
FORCEPROP 1 LAST PATH I291
J 0
(-3425 3625);
DISPLAY 0.978723 (-3425 3625);
PAINT WHITE (-3425 3625);
DISPLAY INVISIBLE (-3425 3625);
FORCEPROP 0 LAST CDS_LOCATION R3771
J 0
(-3425 3625);
DISPLAY 1.021277 (-3425 3625);
DISPLAY INVISIBLE (-3425 3625);
FORCEPROP 0 LAST $SEC 1
J 0
(-3425 3625);
DISPLAY 0.680851 (-3425 3625);
PAINT MONO (-3425 3625);
DISPLAY INVISIBLE (-3425 3625);
FORCEPROP 0 LAST CDS_SEC 1
J 0
(-3425 3625);
DISPLAY 1.021277 (-3425 3625);
DISPLAY INVISIBLE (-3425 3625);
FORCEADD OFFPAGE..2
(-2800 3175);
FORCEPROP 2 LAST $XR0 191 
J 0
(-2611 3175);
DISPLAY 0.638298 (-2611 3175);
PAINT MONO (-2611 3175);
FORCEPROP 2 LAST CDS_LIB standard
J 0
(-2800 3175);
DISPLAY INVISIBLE (-2800 3175);
FORCEPROP 1 LAST OFFPAGE TRUE
J 0
(-2475 3050);
DISPLAY 0.872340 (-2475 3050);
PAINT GREEN (-2475 3050);
DISPLAY INVISIBLE (-2475 3050);
FORCEPROP 1 LAST COMMENT_BODY TRUE
J 0
(-2845 3080);
DISPLAY 0.872340 (-2845 3080);
PAINT GREEN (-2845 3080);
DISPLAY INVISIBLE (-2845 3080);
FORCEPROP 2 LAST PATH I292
J 0
(-2450 3225);
DISPLAY 1.021277 (-2450 3225);
DISPLAY INVISIBLE (-2450 3225);
FORCEADD Q_RES..2
(-3475 2950);
FORCEPROP 1 LAST PART_NUMBER CS21002FB06
J 0
(-3435 2775);
DISPLAY 0.638298 (-3435 2775);
DISPLAY INVISIBLE (-3435 2775);
FORCEPROP 1 LAST PACK_TYPE 0402LF
J 0
(-3435 2825);
DISPLAY 0.638298 (-3435 2825);
FORCEPROP 1 LAST VALUE 1K
J 0
(-3430 3025);
DISPLAY 0.638298 (-3430 3025);
FORCEPROP 1 LAST MATERIAL CHIP
J 0
(-3435 2875);
DISPLAY 0.638298 (-3435 2875);
FORCEPROP 1 LAST WATTAGE 1/16W
J 0
(-3435 2925);
DISPLAY 0.638298 (-3435 2925);
FORCEPROP 1 LAST TOLERANCE 1%
J 0
(-3430 2975);
DISPLAY 0.638298 (-3430 2975);
FORCEPROP 1 LAST LOCATION R2296
J 0
(-3430 3075);
DISPLAY 0.978723 (-3430 3075);
FORCEPROP 1 LASTPIN (-3475 3050) $PN 1
J 0
(-3470 3012);
DISPLAY 0.787234 (-3470 3012);
PAINT MONO (-3470 3012);
FORCEPROP 1 LASTPIN (-3475 2850) $PN 2
J 0
(-3470 2860);
DISPLAY 0.787234 (-3470 2860);
PAINT MONO (-3470 2860);
FORCEPROP 2 LAST CDS_LIB pure_quanta
J 0
(-3475 2950);
DISPLAY INVISIBLE (-3475 2950);
FORCEPROP 1 LAST PATH I293
J 0
(-3425 3125);
DISPLAY 0.978723 (-3425 3125);
PAINT WHITE (-3425 3125);
DISPLAY INVISIBLE (-3425 3125);
FORCEPROP 0 LAST $SEC 1
J 0
(-3425 3125);
DISPLAY 0.680851 (-3425 3125);
PAINT MONO (-3425 3125);
DISPLAY INVISIBLE (-3425 3125);
FORCEPROP 0 LAST CDS_SEC 1
J 0
(-3425 3125);
DISPLAY 1.021277 (-3425 3125);
DISPLAY INVISIBLE (-3425 3125);
FORCEADD UNIVERSAL_GND..1
(-3475 2700);
FORCEPROP 3 LASTPIN (-3475 2750) SIG_NAME GND\g
J 0
(-3465 2760);
DISPLAY 0.659574 (-3465 2760);
PAINT MONO (-3465 2760);
DISPLAY INVISIBLE (-3465 2760);
FORCEPROP 2 LAST CDS_LIB logical_power
J 0
(-3475 2700);
DISPLAY INVISIBLE (-3475 2700);
FORCEPROP 1 LAST HDL_POWER GND
J 1
(-3450 2625);
DISPLAY 0.872340 (-3450 2625);
PAINT GREEN (-3450 2625);
DISPLAY INVISIBLE (-3450 2625);
FORCEPROP 1 LAST PATH I294
J 0
(-3400 2700);
DISPLAY 0.872340 (-3400 2700);
PAINT AQUA (-3400 2700);
DISPLAY INVISIBLE (-3400 2700);
FORCEADD UNIVERSAL_POWER..1
(2775 150);
FORCEPROP 3 LASTPIN (2775 100) SIG_NAME P3V3_AUX\g
J 0
(2785 110);
DISPLAY 0.659574 (2785 110);
PAINT MONO (2785 110);
DISPLAY INVISIBLE (2785 110);
FORCEPROP 1 LAST HDL_POWER P3V3_AUX
J 1
(2775 200);
DISPLAY 0.872340 (2775 200);
PAINT GREEN (2775 200);
FORCEPROP 2 LAST CDS_LIB logical_power
J 0
(2775 150);
DISPLAY INVISIBLE (2775 150);
FORCEPROP 1 LAST PATH I295
J 0
(2825 175);
DISPLAY 0.872340 (2825 175);
PAINT AQUA (2825 175);
DISPLAY INVISIBLE (2825 175);
FORCEADD Q_RES..2
(3050 -200);
FORCEPROP 1 LAST PART_NUMBER CS24702JB10
J 0
(3090 -325);
DISPLAY 0.638298 (3090 -325);
DISPLAY INVISIBLE (3090 -325);
FORCEPROP 1 LAST TOLERANCE 5%
J 0
(3095 -175);
DISPLAY 0.638298 (3095 -175);
FORCEPROP 1 LAST VALUE 4.7K
J 0
(3095 -125);
DISPLAY 0.638298 (3095 -125);
FORCEPROP 1 LAST PACK_TYPE 0402LF
J 0
(3090 -375);
DISPLAY 0.638298 (3090 -375);
FORCEPROP 1 LAST MATERIAL CHIP
J 0
(3090 -275);
DISPLAY 0.638298 (3090 -275);
FORCEPROP 1 LAST WATTAGE 1/16W
J 0
(3090 -225);
DISPLAY 0.638298 (3090 -225);
FORCEPROP 1 LAST $LOCATION R2125
J 0
(3095 -75);
DISPLAY 0.638298 (3095 -75);
FORCEPROP 1 LASTPIN (3050 -100) $PN 1
J 0
(3055 -138);
DISPLAY 0.787234 (3055 -138);
PAINT MONO (3055 -138);
FORCEPROP 1 LASTPIN (3050 -300) $PN 2
J 0
(3055 -290);
DISPLAY 0.787234 (3055 -290);
PAINT MONO (3055 -290);
FORCEPROP 2 LAST CDS_LIB pure_quanta
J 0
(3050 -200);
DISPLAY INVISIBLE (3050 -200);
FORCEPROP 1 LAST PATH I296
J 0
(3100 -25);
DISPLAY 0.978723 (3100 -25);
PAINT WHITE (3100 -25);
DISPLAY INVISIBLE (3100 -25);
FORCEPROP 0 LAST CDS_LOCATION R2125
J 0
(3100 -25);
DISPLAY 1.021277 (3100 -25);
DISPLAY INVISIBLE (3100 -25);
FORCEPROP 0 LAST $SEC 1
J 0
(3100 -25);
DISPLAY 0.680851 (3100 -25);
PAINT MONO (3100 -25);
DISPLAY INVISIBLE (3100 -25);
FORCEPROP 0 LAST CDS_SEC 1
J 0
(3100 -25);
DISPLAY 1.021277 (3100 -25);
DISPLAY INVISIBLE (3100 -25);
FORCEADD OFFPAGE..2
(3225 -650);
FORCEPROP 2 LAST $XR0 194 
J 0
(3414 -650);
DISPLAY 0.638298 (3414 -650);
PAINT MONO (3414 -650);
FORCEPROP 2 LAST CDS_LIB standard
J 0
(3225 -650);
PAINT MONO (3225 -650);
DISPLAY INVISIBLE (3225 -650);
FORCEPROP 1 LAST OFFPAGE TRUE
J 0
(3550 -775);
DISPLAY 0.872340 (3550 -775);
PAINT GREEN (3550 -775);
DISPLAY INVISIBLE (3550 -775);
FORCEPROP 1 LAST COMMENT_BODY TRUE
J 0
(3180 -745);
DISPLAY 0.872340 (3180 -745);
PAINT GREEN (3180 -745);
DISPLAY INVISIBLE (3180 -745);
FORCEPROP 2 LAST PATH I297
J 0
(3425 -600);
DISPLAY 1.021277 (3425 -600);
DISPLAY INVISIBLE (3425 -600);
FORCEADD OFFPAGE..2
(3225 -550);
FORCEPROP 2 LAST $XR0 191 
J 0
(3414 -550);
DISPLAY 0.638298 (3414 -550);
PAINT MONO (3414 -550);
FORCEPROP 2 LAST CDS_LIB standard
J 0
(3225 -550);
PAINT MONO (3225 -550);
DISPLAY INVISIBLE (3225 -550);
FORCEPROP 1 LAST OFFPAGE TRUE
J 0
(3550 -675);
DISPLAY 0.872340 (3550 -675);
PAINT GREEN (3550 -675);
DISPLAY INVISIBLE (3550 -675);
FORCEPROP 1 LAST COMMENT_BODY TRUE
J 0
(3180 -645);
DISPLAY 0.872340 (3180 -645);
PAINT GREEN (3180 -645);
DISPLAY INVISIBLE (3180 -645);
FORCEPROP 2 LAST PATH I298
J 0
(3425 -500);
DISPLAY 1.021277 (3425 -500);
DISPLAY INVISIBLE (3425 -500);
FORCEADD Q_RES..2
(2775 -200);
FORCEPROP 1 LAST PART_NUMBER CS24702JB10
J 0
(2815 -325);
DISPLAY 0.638298 (2815 -325);
DISPLAY INVISIBLE (2815 -325);
FORCEPROP 1 LAST VALUE 4.7K
J 0
(2820 -125);
DISPLAY 0.638298 (2820 -125);
FORCEPROP 1 LAST WATTAGE 1/16W
J 0
(2815 -225);
DISPLAY 0.638298 (2815 -225);
FORCEPROP 1 LAST TOLERANCE 5%
J 0
(2820 -175);
DISPLAY 0.638298 (2820 -175);
FORCEPROP 1 LAST PACK_TYPE 0402LF
J 0
(2825 -325);
DISPLAY 0.638298 (2825 -325);
FORCEPROP 1 LAST MATERIAL EMPTY
J 0
(2815 -275);
DISPLAY 0.638298 (2815 -275);
PAINT RED (2815 -275);
FORCEPROP 1 LAST $LOCATION R3773
J 0
(2820 -75);
DISPLAY 0.638298 (2820 -75);
FORCEPROP 1 LASTPIN (2775 -100) $PN 1
J 0
(2780 -138);
DISPLAY 0.787234 (2780 -138);
PAINT MONO (2780 -138);
FORCEPROP 1 LASTPIN (2775 -300) $PN 2
J 0
(2780 -290);
DISPLAY 0.787234 (2780 -290);
PAINT MONO (2780 -290);
FORCEPROP 1 LAST PATH I299
J 0
(2825 -25);
DISPLAY 0.978723 (2825 -25);
PAINT WHITE (2825 -25);
DISPLAY INVISIBLE (2825 -25);
FORCEPROP 2 LAST CDS_LIB pure_quanta
J 0
(2775 -200);
DISPLAY INVISIBLE (2775 -200);
FORCEPROP 0 LAST CDS_LOCATION R3773
J 0
(2825 -25);
DISPLAY 1.021277 (2825 -25);
DISPLAY INVISIBLE (2825 -25);
FORCEPROP 0 LAST $SEC 1
J 0
(2825 -25);
DISPLAY 0.680851 (2825 -25);
PAINT MONO (2825 -25);
DISPLAY INVISIBLE (2825 -25);
FORCEPROP 0 LAST CDS_SEC 1
J 0
(2825 -25);
DISPLAY 1.021277 (2825 -25);
DISPLAY INVISIBLE (2825 -25);
FORCEADD UNIVERSAL_POWER..1
(950 125);
FORCEPROP 3 LASTPIN (950 75) SIG_NAME P3V3_AUX\g
J 0
(960 85);
DISPLAY 0.659574 (960 85);
PAINT MONO (960 85);
DISPLAY INVISIBLE (960 85);
FORCEPROP 1 LAST HDL_POWER P3V3_AUX
J 1
(950 175);
DISPLAY 0.872340 (950 175);
PAINT GREEN (950 175);
FORCEPROP 2 LAST CDS_LIB logical_power
J 0
(950 125);
DISPLAY INVISIBLE (950 125);
FORCEPROP 1 LAST PATH I300
J 0
(1000 150);
DISPLAY 0.872340 (1000 150);
PAINT AQUA (1000 150);
DISPLAY INVISIBLE (1000 150);
FORCEADD Q_RES..1
(1750 -550);
FORCEPROP 1 LAST PART_NUMBER CS00002JB13
J 0
(1650 -500);
DISPLAY 0.404255 (1650 -500);
DISPLAY INVISIBLE (1650 -500);
FORCEPROP 1 LAST PACK_TYPE 0402LF
J 0
(1650 -475);
DISPLAY 0.404255 (1650 -475);
FORCEPROP 1 LAST VALUE 0
J 2
(1900 -550);
DISPLAY 0.510638 (1900 -550);
FORCEPROP 1 LAST TOLERANCE 5%
J 0
(1925 -550);
DISPLAY 0.510638 (1925 -550);
FORCEPROP 1 LAST MATERIAL CHIP
J 0
(2000 -550);
DISPLAY 0.510638 (2000 -550);
FORCEPROP 1 LAST WATTAGE 1/16W
J 2
(1875 -475);
DISPLAY 0.404255 (1875 -475);
FORCEPROP 1 LAST $LOCATION R3772
J 0
(1525 -550);
DISPLAY 0.638298 (1525 -550);
FORCEPROP 1 LASTPIN (1650 -550) $PN 1
J 0
(1662 -538);
DISPLAY 0.787234 (1662 -538);
PAINT MONO (1662 -538);
FORCEPROP 1 LASTPIN (1850 -550) $PN 2
J 0
(1812 -538);
DISPLAY 0.787234 (1812 -538);
PAINT MONO (1812 -538);
FORCEPROP 2 LAST CDS_LIB pure_quanta
J 0
(1750 -550);
DISPLAY INVISIBLE (1750 -550);
FORCEPROP 1 LAST PATH I301
J 0
(1700 -400);
DISPLAY 0.978723 (1700 -400);
PAINT WHITE (1700 -400);
DISPLAY INVISIBLE (1700 -400);
FORCEPROP 0 LAST CDS_LOCATION R3772
J 0
(1875 -450);
DISPLAY 1.021277 (1875 -450);
DISPLAY INVISIBLE (1875 -450);
FORCEPROP 0 LAST $SEC 1
J 0
(1875 -450);
DISPLAY 0.680851 (1875 -450);
PAINT MONO (1875 -450);
DISPLAY INVISIBLE (1875 -450);
FORCEPROP 0 LAST CDS_SEC 1
J 0
(1875 -450);
DISPLAY 1.021277 (1875 -450);
DISPLAY INVISIBLE (1875 -450);
FORCEADD Q_RES..1
(1750 -650);
FORCEPROP 1 LAST PART_NUMBER CS00002JB13
J 0
(1650 -600);
DISPLAY 0.404255 (1650 -600);
DISPLAY INVISIBLE (1650 -600);
FORCEPROP 1 LAST VALUE 0
J 2
(1900 -650);
DISPLAY 0.510638 (1900 -650);
FORCEPROP 1 LAST TOLERANCE 5%
J 0
(1925 -650);
DISPLAY 0.510638 (1925 -650);
FORCEPROP 1 LAST MATERIAL CHIP
J 0
(2000 -650);
DISPLAY 0.510638 (2000 -650);
FORCEPROP 1 LAST $LOCATION R2114
J 0
(1525 -650);
DISPLAY 0.638298 (1525 -650);
FORCEPROP 1 LASTPIN (1650 -650) $PN 1
J 0
(1662 -638);
DISPLAY 0.787234 (1662 -638);
PAINT MONO (1662 -638);
FORCEPROP 1 LASTPIN (1850 -650) $PN 2
J 0
(1812 -638);
DISPLAY 0.787234 (1812 -638);
PAINT MONO (1812 -638);
FORCEPROP 1 LAST WATTAGE 1/16W
J 2
(1875 -575);
DISPLAY 0.404255 (1875 -575);
DISPLAY INVISIBLE (1875 -575);
FORCEPROP 1 LAST PACK_TYPE 0402LF
J 0
(1650 -575);
DISPLAY 0.404255 (1650 -575);
DISPLAY INVISIBLE (1650 -575);
FORCEPROP 2 LAST CDS_LIB pure_quanta
J 0
(1750 -650);
DISPLAY INVISIBLE (1750 -650);
FORCEPROP 1 LAST PATH I302
J 0
(1700 -500);
DISPLAY 0.978723 (1700 -500);
PAINT WHITE (1700 -500);
DISPLAY INVISIBLE (1700 -500);
FORCEPROP 0 LAST CDS_LOCATION R2114
J 0
(1525 -600);
DISPLAY 1.021277 (1525 -600);
DISPLAY INVISIBLE (1525 -600);
FORCEPROP 0 LAST $SEC 1
J 0
(1525 -600);
DISPLAY 0.680851 (1525 -600);
PAINT MONO (1525 -600);
DISPLAY INVISIBLE (1525 -600);
FORCEPROP 0 LAST CDS_SEC 1
J 0
(1525 -600);
DISPLAY 1.021277 (1525 -600);
DISPLAY INVISIBLE (1525 -600);
FORCEADD UNIVERSAL_GND..1
(950 -425);
FORCEPROP 3 LASTPIN (950 -375) SIG_NAME GND\g
J 0
(960 -365);
DISPLAY 0.659574 (960 -365);
PAINT MONO (960 -365);
DISPLAY INVISIBLE (960 -365);
FORCEPROP 2 LAST CDS_LIB logical_power
J 0
(950 -425);
DISPLAY INVISIBLE (950 -425);
FORCEPROP 1 LAST HDL_POWER GND
J 1
(975 -500);
DISPLAY 0.872340 (975 -500);
PAINT GREEN (975 -500);
DISPLAY INVISIBLE (975 -500);
FORCEPROP 1 LAST PATH I303
J 0
(1025 -425);
DISPLAY 0.872340 (1025 -425);
PAINT AQUA (1025 -425);
DISPLAY INVISIBLE (1025 -425);
FORCEADD Q_CAP..1
(950 -200);
FORCEPROP 1 LAST PART_NUMBER CH4104K1B00
J 0
(1000 -350);
DISPLAY 0.510638 (1000 -350);
DISPLAY INVISIBLE (1000 -350);
FORCEPROP 1 LAST TOLERANCE 10%
J 0
(1000 -250);
DISPLAY 0.510638 (1000 -250);
FORCEPROP 1 LAST VOLTAGE 25V
J 0
(1000 -200);
DISPLAY 0.510638 (1000 -200);
FORCEPROP 1 LAST VALUE 0.1UF
J 0
(1000 -150);
DISPLAY 0.510638 (1000 -150);
FORCEPROP 1 LAST MATERIAL X7R
J 0
(1000 -300);
DISPLAY 0.510638 (1000 -300);
FORCEPROP 1 LAST PACK_TYPE 0402
J 0
(1000 -400);
DISPLAY 0.510638 (1000 -400);
FORCEPROP 1 LAST $LOCATION C1592
J 0
(1000 -100);
DISPLAY 0.978723 (1000 -100);
FORCEPROP 1 LASTPIN (950 -100) $PN 1
J 0
(960 -120);
DISPLAY 0.787234 (960 -120);
PAINT MONO (960 -120);
FORCEPROP 1 LASTPIN (950 -300) $PN 2
J 0
(960 -320);
DISPLAY 0.787234 (960 -320);
PAINT MONO (960 -320);
FORCEPROP 2 LAST CDS_LIB pure_quanta
J 2
(950 -200);
DISPLAY INVISIBLE (950 -200);
FORCEPROP 1 LAST PATH I304
J 0
(1000 -50);
DISPLAY 0.978723 (1000 -50);
PAINT WHITE (1000 -50);
DISPLAY INVISIBLE (1000 -50);
FORCEPROP 0 LAST CDS_LOCATION C1592
J 0
(1000 -50);
DISPLAY 1.021277 (1000 -50);
DISPLAY INVISIBLE (1000 -50);
FORCEPROP 0 LAST $SEC 1
J 0
(1000 -50);
DISPLAY 0.680851 (1000 -50);
PAINT MONO (1000 -50);
DISPLAY INVISIBLE (1000 -50);
FORCEPROP 0 LAST CDS_SEC 1
J 0
(1000 -50);
DISPLAY 1.021277 (1000 -50);
DISPLAY INVISIBLE (1000 -50);
FORCEADD 74LVC2G07DW7..1
(250 -600);
FORCEPROP 1 LAST PART_NUMBER AL002G07003
J 0
(81 -366);
DISPLAY 0.723404 (81 -366);
PAINT GREEN (81 -366);
DISPLAY INVISIBLE (81 -366);
FORCEPROP 2 LAST VALUE 74LVC2G07DW-7
J 0
(100 -175);
DISPLAY 1.021277 (100 -175);
FORCEPROP 2 LAST PART_TYPE SMLF
J 0
(100 -125);
DISPLAY 1.021277 (100 -125);
FORCEPROP 1 LAST MATERIAL IC
J 0
(81 -493);
DISPLAY 0.723404 (81 -493);
PAINT GREEN (81 -493);
FORCEPROP 1 LAST LOCATION U134
J 0
(81 -219);
DISPLAY 0.723404 (81 -219);
PAINT GREEN (81 -219);
FORCEPROP 0 LASTPIN (-75 -550) $PN 1
J 2
(-85 -540);
DISPLAY 0.680851 (-85 -540);
PAINT MONO (-85 -540);
FORCEPROP 0 LASTPIN (575 -550) $PN 6
J 0
(585 -540);
DISPLAY 0.680851 (585 -540);
PAINT MONO (585 -540);
FORCEPROP 0 LASTPIN (-75 -650) $PN 3
J 2
(-85 -640);
DISPLAY 0.680851 (-85 -640);
PAINT MONO (-85 -640);
FORCEPROP 0 LASTPIN (575 -650) $PN 4
J 0
(585 -640);
DISPLAY 0.680851 (585 -640);
PAINT MONO (585 -640);
FORCEPROP 0 LASTPIN (-75 -600) $PN 2
J 2
(-85 -590);
DISPLAY 0.680851 (-85 -590);
PAINT MONO (-85 -590);
FORCEPROP 0 LASTPIN (575 -600) $PN 5
J 0
(585 -590);
DISPLAY 0.680851 (585 -590);
PAINT MONO (585 -590);
FORCEPROP 1 LAST NEEDS_NO_SIZE TRUE
J 0
(250 -600);
DISPLAY 0.723404 (250 -600);
PAINT GREEN (250 -600);
DISPLAY INVISIBLE (250 -600);
FORCEPROP 1 LAST CDS_LMAN_SYM_OUTLINE -175,100,175,-100
J 0
(250 -600);
DISPLAY 0.468085 (250 -600);
PAINT GREEN (250 -600);
DISPLAY INVISIBLE (250 -600);
FORCEPROP 2 LAST CDS_LIB pure_quanta
J 0
(250 -600);
DISPLAY INVISIBLE (250 -600);
FORCEPROP 1 LAST PATH I305
J 0
(250 -600);
DISPLAY 0.723404 (250 -600);
PAINT GREEN (250 -600);
DISPLAY INVISIBLE (250 -600);
FORCEPROP 0 LAST $SEC 1
J 0
(100 -75);
DISPLAY 0.680851 (100 -75);
PAINT MONO (100 -75);
DISPLAY INVISIBLE (100 -75);
FORCEPROP 0 LAST CDS_SEC 1
J 0
(100 -75);
DISPLAY 1.021277 (100 -75);
DISPLAY INVISIBLE (100 -75);
FORCEADD UNIVERSAL_GND..1
(-175 -825);
FORCEPROP 3 LASTPIN (-175 -775) SIG_NAME GND\g
J 0
(-165 -765);
DISPLAY 0.659574 (-165 -765);
PAINT MONO (-165 -765);
DISPLAY INVISIBLE (-165 -765);
FORCEPROP 2 LAST CDS_LIB logical_power
J 0
(-175 -825);
DISPLAY INVISIBLE (-175 -825);
FORCEPROP 1 LAST HDL_POWER GND
J 1
(-150 -900);
DISPLAY 0.872340 (-150 -900);
PAINT GREEN (-150 -900);
DISPLAY INVISIBLE (-150 -900);
FORCEPROP 1 LAST PATH I306
J 0
(-100 -825);
DISPLAY 0.872340 (-100 -825);
PAINT AQUA (-100 -825);
DISPLAY INVISIBLE (-100 -825);
FORCEADD Q_RES..1
(-1000 -550);
FORCEPROP 1 LAST PART_NUMBER CS00002JB13
J 0
(-1100 -500);
DISPLAY 0.404255 (-1100 -500);
DISPLAY INVISIBLE (-1100 -500);
FORCEPROP 1 LAST TOLERANCE 5%
J 0
(-825 -550);
DISPLAY 0.510638 (-825 -550);
FORCEPROP 1 LAST VALUE 0
J 2
(-850 -550);
DISPLAY 0.510638 (-850 -550);
FORCEPROP 1 LAST MATERIAL CHIP
J 0
(-750 -550);
DISPLAY 0.510638 (-750 -550);
FORCEPROP 1 LAST $LOCATION R3775
J 0
(-1050 -500);
DISPLAY 0.978723 (-1050 -500);
FORCEPROP 1 LASTPIN (-1100 -550) $PN 1
J 0
(-1088 -538);
DISPLAY 0.787234 (-1088 -538);
PAINT MONO (-1088 -538);
FORCEPROP 1 LASTPIN (-900 -550) $PN 2
J 0
(-938 -538);
DISPLAY 0.787234 (-938 -538);
PAINT MONO (-938 -538);
FORCEPROP 2 LAST CDS_LIB pure_quanta
J 0
(-1000 -550);
DISPLAY INVISIBLE (-1000 -550);
FORCEPROP 1 LAST PACK_TYPE 0402LF
J 0
(-1100 -475);
DISPLAY 0.404255 (-1100 -475);
DISPLAY INVISIBLE (-1100 -475);
FORCEPROP 1 LAST WATTAGE 1/16W
J 2
(-875 -475);
DISPLAY 0.404255 (-875 -475);
DISPLAY INVISIBLE (-875 -475);
FORCEPROP 1 LAST PATH I307
J 0
(-1050 -400);
DISPLAY 0.978723 (-1050 -400);
PAINT WHITE (-1050 -400);
DISPLAY INVISIBLE (-1050 -400);
FORCEPROP 0 LAST CDS_LOCATION R3775
J 0
(-1050 -450);
DISPLAY 1.021277 (-1050 -450);
DISPLAY INVISIBLE (-1050 -450);
FORCEPROP 0 LAST $SEC 1
J 0
(-1050 -450);
DISPLAY 0.680851 (-1050 -450);
PAINT MONO (-1050 -450);
DISPLAY INVISIBLE (-1050 -450);
FORCEPROP 0 LAST CDS_SEC 1
J 0
(-1050 -450);
DISPLAY 1.021277 (-1050 -450);
DISPLAY INVISIBLE (-1050 -450);
FORCEADD OFFPAGE..1
(-1725 -550);
FORCEPROP 2 LAST $XR7 245 
J 0
(-2817 -550);
DISPLAY 0.638298 (-2817 -550);
PAINT MONO (-2817 -550);
FORCEPROP 2 LAST $XR6 236 
J 0
(-2697 -550);
DISPLAY 0.638298 (-2697 -550);
PAINT MONO (-2697 -550);
FORCEPROP 2 LAST $XR5 233 
J 0
(-2577 -550);
DISPLAY 0.638298 (-2577 -550);
PAINT MONO (-2577 -550);
FORCEPROP 2 LAST $XR4 231 
J 0
(-2457 -550);
DISPLAY 0.638298 (-2457 -550);
PAINT MONO (-2457 -550);
FORCEPROP 2 LAST $XR3 227 
J 0
(-2337 -550);
DISPLAY 0.638298 (-2337 -550);
PAINT MONO (-2337 -550);
FORCEPROP 2 LAST $XR2 161 
J 0
(-2217 -550);
DISPLAY 0.638298 (-2217 -550);
PAINT MONO (-2217 -550);
FORCEPROP 2 LAST $XR1 154 
J 0
(-2097 -550);
DISPLAY 0.638298 (-2097 -550);
PAINT MONO (-2097 -550);
FORCEPROP 2 LAST $XR0 215 
J 0
(-1977 -550);
DISPLAY 0.638298 (-1977 -550);
PAINT MONO (-1977 -550);
FORCEPROP 2 LAST CDS_LIB standard
J 0
(-1725 -550);
DISPLAY INVISIBLE (-1725 -550);
FORCEPROP 1 LAST OFFPAGE TRUE
J 0
(-1400 -675);
DISPLAY 0.872340 (-1400 -675);
PAINT GREEN (-1400 -675);
DISPLAY INVISIBLE (-1400 -675);
FORCEPROP 1 LAST COMMENT_BODY TRUE
J 0
(-1600 -650);
DISPLAY 0.872340 (-1600 -650);
PAINT GREEN (-1600 -650);
DISPLAY INVISIBLE (-1600 -650);
FORCEPROP 2 LAST PATH I308
J 0
(-2000 -525);
DISPLAY 1.021277 (-2000 -525);
DISPLAY INVISIBLE (-2000 -525);
FORCEADD Q_RES..1
(-2000 4200);
FORCEPROP 1 LAST PART_NUMBER CS00002JB13
J 0
(-2100 4250);
DISPLAY 0.319149 (-2100 4250);
DISPLAY INVISIBLE (-2100 4250);
FORCEPROP 1 LAST PACK_TYPE 0402LF
J 0
(-2100 4275);
DISPLAY 0.319149 (-2100 4275);
FORCEPROP 1 LAST VALUE 0
J 2
(-1825 4200);
DISPLAY 0.638298 (-1825 4200);
FORCEPROP 1 LAST MATERIAL CHIP
J 0
(-1725 4200);
DISPLAY 0.638298 (-1725 4200);
FORCEPROP 1 LAST WATTAGE 1/16W
J 2
(-1925 4275);
DISPLAY 0.319149 (-1925 4275);
FORCEPROP 1 LAST TOLERANCE 5%
J 0
(-1800 4200);
DISPLAY 0.638298 (-1800 4200);
FORCEPROP 1 LAST $LOCATION R3779
J 0
(-2150 4200);
DISPLAY 0.638298 (-2150 4200);
FORCEPROP 1 LASTPIN (-2100 4200) $PN 1
J 0
(-2088 4212);
DISPLAY 0.787234 (-2088 4212);
PAINT MONO (-2088 4212);
FORCEPROP 1 LASTPIN (-1900 4200) $PN 2
J 0
(-1938 4212);
DISPLAY 0.787234 (-1938 4212);
PAINT MONO (-1938 4212);
FORCEPROP 2 LAST CDS_LIB pure_quanta
J 0
(-2000 4200);
DISPLAY INVISIBLE (-2000 4200);
FORCEPROP 1 LAST PATH I309
J 0
(-2050 4350);
DISPLAY 0.978723 (-2050 4350);
PAINT WHITE (-2050 4350);
DISPLAY INVISIBLE (-2050 4350);
FORCEPROP 0 LAST CDS_LOCATION R3779
J 0
(-1925 4300);
DISPLAY 1.021277 (-1925 4300);
DISPLAY INVISIBLE (-1925 4300);
FORCEPROP 0 LAST $SEC 1
J 0
(-1925 4300);
DISPLAY 0.680851 (-1925 4300);
PAINT MONO (-1925 4300);
DISPLAY INVISIBLE (-1925 4300);
FORCEPROP 0 LAST CDS_SEC 1
J 0
(-1925 4300);
DISPLAY 1.021277 (-1925 4300);
DISPLAY INVISIBLE (-1925 4300);
FORCEADD OFFPAGE..1
(-3150 4200);
FORCEPROP 2 LAST $XR0 215 
J 0
(-3402 4200);
DISPLAY 0.638298 (-3402 4200);
PAINT MONO (-3402 4200);
FORCEPROP 2 LAST CDS_LIB standard
J 0
(-3150 4200);
PAINT MONO (-3150 4200);
DISPLAY INVISIBLE (-3150 4200);
FORCEPROP 1 LAST OFFPAGE TRUE
J 0
(-2825 4075);
DISPLAY 0.872340 (-2825 4075);
PAINT GREEN (-2825 4075);
DISPLAY INVISIBLE (-2825 4075);
FORCEPROP 1 LAST COMMENT_BODY TRUE
J 0
(-3025 4100);
DISPLAY 0.872340 (-3025 4100);
PAINT GREEN (-3025 4100);
DISPLAY INVISIBLE (-3025 4100);
FORCEPROP 2 LAST PATH I310
J 0
(-3100 4275);
DISPLAY 1.021277 (-3100 4275);
DISPLAY INVISIBLE (-3100 4275);
FORCEADD Q_RES..2
(3850 3850);
FORCEPROP 1 LAST PART_NUMBER CS11002FB07
J 0
(3890 3675);
DISPLAY 0.510638 (3890 3675);
DISPLAY INVISIBLE (3890 3675);
FORCEPROP 1 LAST VALUE 100
J 0
(3895 3925);
DISPLAY 0.510638 (3895 3925);
FORCEPROP 1 LAST PACK_TYPE 0402LF
J 0
(3890 3725);
DISPLAY 0.510638 (3890 3725);
FORCEPROP 1 LAST MATERIAL EMPTY
J 0
(3890 3775);
DISPLAY 0.510638 (3890 3775);
PAINT RED (3890 3775);
FORCEPROP 1 LAST WATTAGE 1/16W
J 0
(3890 3825);
DISPLAY 0.510638 (3890 3825);
FORCEPROP 1 LAST TOLERANCE 1%
J 0
(3895 3875);
DISPLAY 0.510638 (3895 3875);
FORCEPROP 1 LAST LOCATION R2426
J 0
(3895 3975);
DISPLAY 0.638298 (3895 3975);
FORCEPROP 1 LASTPIN (3850 3950) $PN 1
J 0
(3855 3912);
DISPLAY 0.787234 (3855 3912);
PAINT MONO (3855 3912);
FORCEPROP 1 LASTPIN (3850 3750) $PN 2
J 0
(3855 3760);
DISPLAY 0.787234 (3855 3760);
PAINT MONO (3855 3760);
FORCEPROP 2 LAST CDS_LIB pure_quanta
J 0
(3850 3850);
DISPLAY INVISIBLE (3850 3850);
FORCEPROP 1 LAST PATH I311
J 0
(3900 4025);
DISPLAY 0.978723 (3900 4025);
PAINT WHITE (3900 4025);
DISPLAY INVISIBLE (3900 4025);
FORCEPROP 0 LAST $SEC 1
J 0
(3900 4025);
DISPLAY 0.680851 (3900 4025);
PAINT MONO (3900 4025);
DISPLAY INVISIBLE (3900 4025);
FORCEPROP 0 LAST CDS_SEC 1
J 0
(3900 4025);
DISPLAY 1.021277 (3900 4025);
DISPLAY INVISIBLE (3900 4025);
FORCEADD Q_RES..2
(2300 4625);
FORCEPROP 1 LAST PART_NUMBER CS31002FB08
J 0
(2325 4450);
DISPLAY 0.510638 (2325 4450);
DISPLAY INVISIBLE (2325 4450);
FORCEPROP 1 LAST MATERIAL CHIP
J 0
(2340 4550);
DISPLAY 0.510638 (2340 4550);
FORCEPROP 1 LAST PACK_TYPE 0402LF
J 0
(2340 4500);
DISPLAY 0.510638 (2340 4500);
FORCEPROP 1 LAST VALUE 10K
J 0
(2345 4700);
DISPLAY 0.510638 (2345 4700);
FORCEPROP 1 LAST TOLERANCE 1%
J 0
(2345 4650);
DISPLAY 0.510638 (2345 4650);
FORCEPROP 1 LAST WATTAGE 1/16W
J 0
(2340 4600);
DISPLAY 0.510638 (2340 4600);
FORCEPROP 1 LAST LOCATION R1673
J 0
(2345 4750);
DISPLAY 0.638298 (2345 4750);
FORCEPROP 1 LASTPIN (2300 4725) $PN 1
J 0
(2305 4687);
DISPLAY 0.787234 (2305 4687);
PAINT MONO (2305 4687);
FORCEPROP 1 LASTPIN (2300 4525) $PN 2
J 0
(2305 4535);
DISPLAY 0.787234 (2305 4535);
PAINT MONO (2305 4535);
FORCEPROP 1 LAST PATH I312
J 0
(2350 4800);
DISPLAY 0.978723 (2350 4800);
PAINT WHITE (2350 4800);
DISPLAY INVISIBLE (2350 4800);
FORCEPROP 2 LAST CDS_LIB pure_quanta
J 0
(2300 4625);
DISPLAY INVISIBLE (2300 4625);
FORCEPROP 0 LAST $SEC 1
J 0
(2350 4800);
DISPLAY 0.680851 (2350 4800);
PAINT MONO (2350 4800);
DISPLAY INVISIBLE (2350 4800);
FORCEPROP 0 LAST CDS_SEC 1
J 0
(2350 4800);
DISPLAY 1.021277 (2350 4800);
DISPLAY INVISIBLE (2350 4800);
FORCEADD Q_RES..2
(3775 4650);
FORCEPROP 1 LAST PART_NUMBER CS31002FB08
J 0
(3815 4475);
DISPLAY 0.510638 (3815 4475);
DISPLAY INVISIBLE (3815 4475);
FORCEPROP 1 LAST WATTAGE 1/16W
J 0
(3815 4625);
DISPLAY 0.510638 (3815 4625);
FORCEPROP 1 LAST TOLERANCE 1%
J 0
(3820 4675);
DISPLAY 0.510638 (3820 4675);
FORCEPROP 1 LAST MATERIAL CHIP
J 0
(3815 4575);
DISPLAY 0.510638 (3815 4575);
FORCEPROP 1 LAST VALUE 10K
J 0
(3820 4725);
DISPLAY 0.510638 (3820 4725);
FORCEPROP 1 LAST PACK_TYPE 0402LF
J 0
(3815 4525);
DISPLAY 0.510638 (3815 4525);
FORCEPROP 1 LAST LOCATION R2287
J 0
(3820 4775);
DISPLAY 0.638298 (3820 4775);
FORCEPROP 1 LASTPIN (3775 4750) $PN 1
J 0
(3780 4712);
DISPLAY 0.787234 (3780 4712);
PAINT MONO (3780 4712);
FORCEPROP 1 LASTPIN (3775 4550) $PN 2
J 0
(3780 4560);
DISPLAY 0.787234 (3780 4560);
PAINT MONO (3780 4560);
FORCEPROP 1 LAST PATH I313
J 0
(3825 4825);
DISPLAY 0.978723 (3825 4825);
PAINT WHITE (3825 4825);
DISPLAY INVISIBLE (3825 4825);
FORCEPROP 2 LAST CDS_LIB pure_quanta
J 0
(3775 4650);
DISPLAY INVISIBLE (3775 4650);
FORCEPROP 0 LAST $SEC 1
J 0
(3825 4825);
DISPLAY 0.680851 (3825 4825);
PAINT MONO (3825 4825);
DISPLAY INVISIBLE (3825 4825);
FORCEPROP 0 LAST CDS_SEC 1
J 0
(3825 4825);
DISPLAY 1.021277 (3825 4825);
DISPLAY INVISIBLE (3825 4825);
FORCEADD MOSFET_NCH_GDS_ESD_PROTECTED..1
(2650 1225);
FORCEPROP 1 LAST PART_NUMBER BAM70020002
J 0
(2792 1137);
DISPLAY 0.723404 (2792 1137);
PAINT GREEN (2792 1137);
DISPLAY INVISIBLE (2792 1137);
FORCEPROP 2 LAST PART_TYPE SMLF
J 0
(2800 1325);
DISPLAY 0.680851 (2800 1325);
FORCEPROP 2 LAST VALUE 2N7002K
J 0
(2800 1275);
DISPLAY 0.680851 (2800 1275);
FORCEPROP 1 LAST MATERIAL IC
J 0
(2792 1080);
DISPLAY 0.723404 (2792 1080);
PAINT GREEN (2792 1080);
FORCEPROP 1 LAST LOCATION Q46
J 0
(2792 1189);
DISPLAY 0.723404 (2792 1189);
PAINT GREEN (2792 1189);
FORCEPROP 0 LASTPIN (2675 1425) $PN D
R 1
J 0
(2665 1435);
DISPLAY 0.680851 (2665 1435);
PAINT MONO (2665 1435);
FORCEPROP 0 LASTPIN (2475 1225) $PN G
J 2
(2465 1235);
DISPLAY 0.680851 (2465 1235);
PAINT MONO (2465 1235);
FORCEPROP 0 LASTPIN (2675 1025) $PN S
R 1
J 2
(2665 1015);
DISPLAY 0.680851 (2665 1015);
PAINT MONO (2665 1015);
FORCEPROP 1 LAST PATH I316
J 0
(2775 1075);
DISPLAY 0.723404 (2775 1075);
PAINT GREEN (2775 1075);
DISPLAY INVISIBLE (2775 1075);
FORCEPROP 1 LAST NEEDS_NO_SIZE TRUE
J 0
(2775 1115);
DISPLAY 0.723404 (2775 1115);
PAINT GREEN (2775 1115);
DISPLAY INVISIBLE (2775 1115);
FORCEPROP 2 LAST CDS_LIB pure_quanta
J 0
(2650 1225);
DISPLAY INVISIBLE (2650 1225);
FORCEPROP 1 LAST CDS_LMAN_SYM_OUTLINE -125,150,125,-150
J 0
(2650 1225);
DISPLAY 0.468085 (2650 1225);
PAINT GREEN (2650 1225);
DISPLAY INVISIBLE (2650 1225);
FORCEPROP 0 LAST $SEC 1
J 0
(2800 1375);
DISPLAY 0.680851 (2800 1375);
PAINT MONO (2800 1375);
DISPLAY INVISIBLE (2800 1375);
FORCEPROP 0 LAST CDS_SEC 1
J 0
(2800 1375);
DISPLAY 1.021277 (2800 1375);
DISPLAY INVISIBLE (2800 1375);
FORCEADD UNIVERSAL_GND..1
(2675 900);
FORCEPROP 3 LASTPIN (2675 950) SIG_NAME GND\g
J 0
(2685 960);
DISPLAY 0.659574 (2685 960);
PAINT MONO (2685 960);
DISPLAY INVISIBLE (2685 960);
FORCEPROP 1 LAST PATH I317
J 0
(2750 900);
DISPLAY 0.872340 (2750 900);
PAINT AQUA (2750 900);
DISPLAY INVISIBLE (2750 900);
FORCEPROP 1 LAST HDL_POWER GND
J 1
(2700 825);
DISPLAY 0.872340 (2700 825);
PAINT GREEN (2700 825);
DISPLAY INVISIBLE (2700 825);
FORCEPROP 2 LAST CDS_LIB logical_power
J 0
(2675 900);
DISPLAY INVISIBLE (2675 900);
FORCEADD SCONN56_123276793..1
(500 3875);
FORCEPROP 1 LAST PART_NUMBER DFHS56FS022
J 0
(-70 4909);
DISPLAY 0.723404 (-70 4909);
PAINT GREEN (-70 4909);
DISPLAY INVISIBLE (-70 4909);
FORCEPROP 2 LAST VALUE SCONN56_1-2327679-3
J 0
(-50 5100);
DISPLAY 1.021277 (-50 5100);
FORCEPROP 1 LAST MATERIAL IO
J 0
(-70 4782);
DISPLAY 0.723404 (-70 4782);
PAINT GREEN (-70 4782);
FORCEPROP 2 LAST PART_TYPE SMLF
J 0
(-50 5150);
DISPLAY 1.021277 (-50 5150);
FORCEPROP 1 LAST LOCATION J90
J 0
(-70 5056);
DISPLAY 0.723404 (-70 5056);
PAINT GREEN (-70 5056);
FORCEPROP 0 LASTPIN (-225 4250) $PN B9
J 2
(-235 4260);
DISPLAY 0.680851 (-235 4260);
PAINT MONO (-235 4260);
FORCEPROP 0 LASTPIN (1225 3150) $PN G1
J 0
(1235 3160);
DISPLAY 0.680851 (1235 3160);
PAINT MONO (1235 3160);
FORCEPROP 0 LASTPIN (-225 3150) $PN G2
J 2
(-235 3160);
DISPLAY 0.680851 (-235 3160);
PAINT MONO (-235 3160);
FORCEPROP 0 LASTPIN (1225 4700) $PN A1
J 0
(1235 4710);
DISPLAY 0.680851 (1235 4710);
PAINT MONO (1235 4710);
FORCEPROP 0 LASTPIN (1225 4650) $PN A2
J 0
(1235 4660);
DISPLAY 0.680851 (1235 4660);
PAINT MONO (1235 4660);
FORCEPROP 0 LASTPIN (1225 4600) $PN A3
J 0
(1235 4610);
DISPLAY 0.680851 (1235 4610);
PAINT MONO (1235 4610);
FORCEPROP 0 LASTPIN (1225 4550) $PN A4
J 0
(1235 4560);
DISPLAY 0.680851 (1235 4560);
PAINT MONO (1235 4560);
FORCEPROP 0 LASTPIN (1225 4500) $PN A5
J 0
(1235 4510);
DISPLAY 0.680851 (1235 4510);
PAINT MONO (1235 4510);
FORCEPROP 0 LASTPIN (1225 4450) $PN A6
J 0
(1235 4460);
DISPLAY 0.680851 (1235 4460);
PAINT MONO (1235 4460);
FORCEPROP 0 LASTPIN (1225 4000) $PN A13
J 0
(1235 4010);
DISPLAY 0.680851 (1235 4010);
PAINT MONO (1235 4010);
FORCEPROP 0 LASTPIN (1225 3850) $PN A16
J 0
(1235 3860);
DISPLAY 0.680851 (1235 3860);
PAINT MONO (1235 3860);
FORCEPROP 0 LASTPIN (1225 3700) $PN A19
J 0
(1235 3710);
DISPLAY 0.680851 (1235 3710);
PAINT MONO (1235 3710);
FORCEPROP 0 LASTPIN (1225 3550) $PN A22
J 0
(1235 3560);
DISPLAY 0.680851 (1235 3560);
PAINT MONO (1235 3560);
FORCEPROP 0 LASTPIN (1225 3400) $PN A25
J 0
(1235 3410);
DISPLAY 0.680851 (1235 3410);
PAINT MONO (1235 3410);
FORCEPROP 0 LASTPIN (1225 3250) $PN A28
J 0
(1235 3260);
DISPLAY 0.680851 (1235 3260);
PAINT MONO (1235 3260);
FORCEPROP 0 LASTPIN (-225 4000) $PN B13
J 2
(-235 4010);
DISPLAY 0.680851 (-235 4010);
PAINT MONO (-235 4010);
FORCEPROP 0 LASTPIN (-225 3850) $PN B16
J 2
(-235 3860);
DISPLAY 0.680851 (-235 3860);
PAINT MONO (-235 3860);
FORCEPROP 0 LASTPIN (-225 3700) $PN B19
J 2
(-235 3710);
DISPLAY 0.680851 (-235 3710);
PAINT MONO (-235 3710);
FORCEPROP 0 LASTPIN (-225 3550) $PN B22
J 2
(-235 3560);
DISPLAY 0.680851 (-235 3560);
PAINT MONO (-235 3560);
FORCEPROP 0 LASTPIN (-225 3400) $PN B25
J 2
(-235 3410);
DISPLAY 0.680851 (-235 3410);
PAINT MONO (-235 3410);
FORCEPROP 0 LASTPIN (-225 3250) $PN B28
J 2
(-235 3260);
DISPLAY 0.680851 (-235 3260);
PAINT MONO (-235 3260);
FORCEPROP 0 LASTPIN (1225 4200) $PN A10
J 0
(1235 4210);
DISPLAY 0.680851 (1235 4210);
PAINT MONO (1235 4210);
FORCEPROP 0 LASTPIN (-225 4350) $PN B7
J 2
(-235 4360);
DISPLAY 0.680851 (-235 4360);
PAINT MONO (-235 4360);
FORCEPROP 0 LASTPIN (-225 4150) $PN B11
J 2
(-235 4160);
DISPLAY 0.680851 (-235 4160);
PAINT MONO (-235 4160);
FORCEPROP 0 LASTPIN (-225 4700) $PN B1
J 2
(-235 4710);
DISPLAY 0.680851 (-235 4710);
PAINT MONO (-235 4710);
FORCEPROP 0 LASTPIN (-225 4650) $PN B2
J 2
(-235 4660);
DISPLAY 0.680851 (-235 4660);
PAINT MONO (-235 4660);
FORCEPROP 0 LASTPIN (-225 4600) $PN B3
J 2
(-235 4610);
DISPLAY 0.680851 (-235 4610);
PAINT MONO (-235 4610);
FORCEPROP 0 LASTPIN (-225 4550) $PN B4
J 2
(-235 4560);
DISPLAY 0.680851 (-235 4560);
PAINT MONO (-235 4560);
FORCEPROP 0 LASTPIN (-225 4500) $PN B5
J 2
(-235 4510);
DISPLAY 0.680851 (-235 4510);
PAINT MONO (-235 4510);
FORCEPROP 0 LASTPIN (-225 4450) $PN B6
J 2
(-235 4460);
DISPLAY 0.680851 (-235 4460);
PAINT MONO (-235 4460);
FORCEPROP 0 LASTPIN (1225 3800) $PN A17
J 0
(1235 3810);
DISPLAY 0.680851 (1235 3810);
PAINT MONO (1235 3810);
FORCEPROP 0 LASTPIN (1225 3650) $PN A20
J 0
(1235 3660);
DISPLAY 0.680851 (1235 3660);
PAINT MONO (1235 3660);
FORCEPROP 0 LASTPIN (1225 3500) $PN A23
J 0
(1235 3510);
DISPLAY 0.680851 (1235 3510);
PAINT MONO (1235 3510);
FORCEPROP 0 LASTPIN (1225 3350) $PN A26
J 0
(1235 3360);
DISPLAY 0.680851 (1235 3360);
PAINT MONO (1235 3360);
FORCEPROP 0 LASTPIN (1225 3750) $PN A18
J 0
(1235 3760);
DISPLAY 0.680851 (1235 3760);
PAINT MONO (1235 3760);
FORCEPROP 0 LASTPIN (1225 3600) $PN A21
J 0
(1235 3610);
DISPLAY 0.680851 (1235 3610);
PAINT MONO (1235 3610);
FORCEPROP 0 LASTPIN (1225 3450) $PN A24
J 0
(1235 3460);
DISPLAY 0.680851 (1235 3460);
PAINT MONO (1235 3460);
FORCEPROP 0 LASTPIN (1225 3300) $PN A27
J 0
(1235 3310);
DISPLAY 0.680851 (1235 3310);
PAINT MONO (1235 3310);
FORCEPROP 0 LASTPIN (-225 4200) $PN B10
J 2
(-235 4210);
DISPLAY 0.680851 (-235 4210);
PAINT MONO (-235 4210);
FORCEPROP 0 LASTPIN (1225 4150) $PN A11
J 0
(1235 4160);
DISPLAY 0.680851 (1235 4160);
PAINT MONO (1235 4160);
FORCEPROP 0 LASTPIN (-225 3800) $PN B17
J 2
(-235 3810);
DISPLAY 0.680851 (-235 3810);
PAINT MONO (-235 3810);
FORCEPROP 0 LASTPIN (-225 3650) $PN B20
J 2
(-235 3660);
DISPLAY 0.680851 (-235 3660);
PAINT MONO (-235 3660);
FORCEPROP 0 LASTPIN (-225 3500) $PN B23
J 2
(-235 3510);
DISPLAY 0.680851 (-235 3510);
PAINT MONO (-235 3510);
FORCEPROP 0 LASTPIN (-225 3350) $PN B26
J 2
(-235 3360);
DISPLAY 0.680851 (-235 3360);
PAINT MONO (-235 3360);
FORCEPROP 0 LASTPIN (-225 3750) $PN B18
J 2
(-235 3760);
DISPLAY 0.680851 (-235 3760);
PAINT MONO (-235 3760);
FORCEPROP 0 LASTPIN (-225 3600) $PN B21
J 2
(-235 3610);
DISPLAY 0.680851 (-235 3610);
PAINT MONO (-235 3610);
FORCEPROP 0 LASTPIN (-225 3450) $PN B24
J 2
(-235 3460);
DISPLAY 0.680851 (-235 3460);
PAINT MONO (-235 3460);
FORCEPROP 0 LASTPIN (-225 3300) $PN B27
J 2
(-235 3310);
DISPLAY 0.680851 (-235 3310);
PAINT MONO (-235 3310);
FORCEPROP 0 LASTPIN (1225 4100) $PN A12
J 0
(1235 4110);
DISPLAY 0.680851 (1235 4110);
PAINT MONO (1235 4110);
FORCEPROP 0 LASTPIN (-225 4100) $PN B12
J 2
(-235 4110);
DISPLAY 0.680851 (-235 4110);
PAINT MONO (-235 4110);
FORCEPROP 0 LASTPIN (-225 3950) $PN B14
J 2
(-235 3960);
DISPLAY 0.680851 (-235 3960);
PAINT MONO (-235 3960);
FORCEPROP 0 LASTPIN (1225 3950) $PN A14
J 0
(1235 3960);
DISPLAY 0.680851 (1235 3960);
PAINT MONO (1235 3960);
FORCEPROP 0 LASTPIN (-225 3900) $PN B15
J 2
(-235 3910);
DISPLAY 0.680851 (-235 3910);
PAINT MONO (-235 3910);
FORCEPROP 0 LASTPIN (1225 3900) $PN A15
J 0
(1235 3910);
DISPLAY 0.680851 (1235 3910);
PAINT MONO (1235 3910);
FORCEPROP 0 LASTPIN (-225 4300) $PN B8
J 2
(-235 4310);
DISPLAY 0.680851 (-235 4310);
PAINT MONO (-235 4310);
FORCEPROP 0 LASTPIN (1225 4350) $PN A7
J 0
(1235 4360);
DISPLAY 0.680851 (1235 4360);
PAINT MONO (1235 4360);
FORCEPROP 0 LASTPIN (1225 4300) $PN A8
J 0
(1235 4310);
DISPLAY 0.680851 (1235 4310);
PAINT MONO (1235 4310);
FORCEPROP 0 LASTPIN (1225 4250) $PN A9
J 0
(1235 4260);
DISPLAY 0.680851 (1235 4260);
PAINT MONO (1235 4260);
FORCEPROP 1 LAST CDS_LMAN_SYM_OUTLINE -575,875,575,-875
J 0
(500 3875);
DISPLAY 0.468085 (500 3875);
PAINT GREEN (500 3875);
DISPLAY INVISIBLE (500 3875);
FORCEPROP 1 LAST NEEDS_NO_SIZE TRUE
J 0
(500 3875);
DISPLAY 0.723404 (500 3875);
PAINT GREEN (500 3875);
DISPLAY INVISIBLE (500 3875);
FORCEPROP 2 LAST CDS_LIB pure_quanta
J 0
(500 3875);
DISPLAY INVISIBLE (500 3875);
FORCEPROP 1 LAST PATH I318
J 0
(500 3875);
DISPLAY 0.723404 (500 3875);
PAINT GREEN (500 3875);
DISPLAY INVISIBLE (500 3875);
FORCEPROP 0 LAST $SEC 1
J 0
(-50 5200);
DISPLAY 0.680851 (-50 5200);
PAINT MONO (-50 5200);
DISPLAY INVISIBLE (-50 5200);
FORCEPROP 0 LAST CDS_SEC 1
J 0
(-50 5200);
DISPLAY 1.021277 (-50 5200);
DISPLAY INVISIBLE (-50 5200);
FORCEADD TAP..1
(1675 3800);
FORCEPROP 3 LASTPIN (1625 3800) SIG_NAME P3E_PCH_E1S_RX_DP<0>
J 0
(1635 3810);
DISPLAY 0.659574 (1635 3810);
PAINT MONO (1635 3810);
DISPLAY INVISIBLE (1635 3810);
FORCEPROP 1 LASTPIN (1625 3800) BN 0
J 0
(1613 3808);
DISPLAY 0.680851 (1613 3808);
PAINT GREEN (1613 3808);
FORCEPROP 2 LAST CDS_LIB standard
J 0
(1675 3800);
PAINT MONO (1675 3800);
DISPLAY INVISIBLE (1675 3800);
FORCEPROP 1 LAST BODY_TYPE PLUMBING
J 0
(1675 3850);
DISPLAY 0.872340 (1675 3850);
PAINT GREEN (1675 3850);
DISPLAY INVISIBLE (1675 3850);
FORCEPROP 1 LAST HDL_TAP TRUE
J 0
(2000 3675);
DISPLAY 0.872340 (2000 3675);
PAINT GREEN (2000 3675);
DISPLAY INVISIBLE (2000 3675);
FORCEPROP 1 LAST PATH I319
J 0
(1673 3800);
DISPLAY 0.872340 (1673 3800);
PAINT GREEN (1673 3800);
DISPLAY INVISIBLE (1673 3800);
FORCEADD TAP..1
(1825 3750);
FORCEPROP 3 LASTPIN (1775 3750) SIG_NAME P3E_PCH_E1S_RX_DN<0>
J 0
(1785 3760);
DISPLAY 0.659574 (1785 3760);
PAINT MONO (1785 3760);
DISPLAY INVISIBLE (1785 3760);
FORCEPROP 1 LASTPIN (1775 3750) BN 0
J 0
(1763 3758);
DISPLAY 0.680851 (1763 3758);
PAINT GREEN (1763 3758);
FORCEPROP 2 LAST CDS_LIB standard
J 0
(1825 3750);
PAINT MONO (1825 3750);
DISPLAY INVISIBLE (1825 3750);
FORCEPROP 1 LAST BODY_TYPE PLUMBING
J 0
(1825 3800);
DISPLAY 0.872340 (1825 3800);
PAINT GREEN (1825 3800);
DISPLAY INVISIBLE (1825 3800);
FORCEPROP 1 LAST HDL_TAP TRUE
J 0
(2150 3625);
DISPLAY 0.872340 (2150 3625);
DISPLAY INVISIBLE (2150 3625);
FORCEPROP 1 LAST PATH I320
J 0
(1823 3750);
DISPLAY 0.872340 (1823 3750);
PAINT GREEN (1823 3750);
DISPLAY INVISIBLE (1823 3750);
FORCEADD TAP..1
R 2
(-625 3800);
FORCEPROP 3 LASTPIN (-575 3800) SIG_NAME P3E_PCH_E1S_TX_C_DP<0>
J 0
(-565 3810);
DISPLAY 0.659574 (-565 3810);
PAINT MONO (-565 3810);
DISPLAY INVISIBLE (-565 3810);
FORCEPROP 1 LASTPIN (-575 3800) BN 0
J 2
(-563 3808);
DISPLAY 0.680851 (-563 3808);
PAINT GREEN (-563 3808);
FORCEPROP 2 LAST CDS_LIB standard
J 0
(-625 3800);
DISPLAY INVISIBLE (-625 3800);
FORCEPROP 1 LAST BODY_TYPE PLUMBING
J 2
(-625 3850);
DISPLAY 0.872340 (-625 3850);
PAINT GREEN (-625 3850);
DISPLAY INVISIBLE (-625 3850);
FORCEPROP 1 LAST HDL_TAP TRUE
J 2
(-950 3675);
DISPLAY 0.872340 (-950 3675);
PAINT GREEN (-950 3675);
DISPLAY INVISIBLE (-950 3675);
FORCEPROP 1 LAST PATH I321
J 2
(-623 3800);
DISPLAY 0.872340 (-623 3800);
PAINT GREEN (-623 3800);
DISPLAY INVISIBLE (-623 3800);
FORCEADD TAP..1
R 2
(-775 3750);
FORCEPROP 3 LASTPIN (-725 3750) SIG_NAME P3E_PCH_E1S_TX_C_DN<0>
J 0
(-715 3760);
DISPLAY 0.659574 (-715 3760);
PAINT MONO (-715 3760);
DISPLAY INVISIBLE (-715 3760);
FORCEPROP 1 LASTPIN (-725 3750) BN 0
J 2
(-713 3758);
DISPLAY 0.680851 (-713 3758);
PAINT GREEN (-713 3758);
FORCEPROP 2 LAST CDS_LIB standard
J 0
(-775 3750);
DISPLAY INVISIBLE (-775 3750);
FORCEPROP 1 LAST BODY_TYPE PLUMBING
J 2
(-775 3800);
DISPLAY 0.872340 (-775 3800);
PAINT GREEN (-775 3800);
DISPLAY INVISIBLE (-775 3800);
FORCEPROP 1 LAST HDL_TAP TRUE
J 2
(-1100 3625);
DISPLAY 0.872340 (-1100 3625);
PAINT GREEN (-1100 3625);
DISPLAY INVISIBLE (-1100 3625);
FORCEPROP 1 LAST PATH I322
J 2
(-773 3750);
DISPLAY 0.872340 (-773 3750);
PAINT GREEN (-773 3750);
DISPLAY INVISIBLE (-773 3750);
FORCEADD TAP..1
R 2
(-625 3650);
FORCEPROP 3 LASTPIN (-575 3650) SIG_NAME P3E_PCH_E1S_TX_C_DP<1>
J 0
(-565 3660);
DISPLAY 0.659574 (-565 3660);
PAINT MONO (-565 3660);
DISPLAY INVISIBLE (-565 3660);
FORCEPROP 1 LASTPIN (-575 3650) BN 1
J 2
(-563 3658);
DISPLAY 0.680851 (-563 3658);
PAINT GREEN (-563 3658);
FORCEPROP 2 LAST CDS_LIB standard
J 0
(-625 3650);
PAINT MONO (-625 3650);
DISPLAY INVISIBLE (-625 3650);
FORCEPROP 1 LAST BODY_TYPE PLUMBING
J 2
(-625 3700);
DISPLAY 0.872340 (-625 3700);
PAINT GREEN (-625 3700);
DISPLAY INVISIBLE (-625 3700);
FORCEPROP 1 LAST HDL_TAP TRUE
J 2
(-950 3525);
DISPLAY 0.872340 (-950 3525);
PAINT GREEN (-950 3525);
DISPLAY INVISIBLE (-950 3525);
FORCEPROP 1 LAST PATH I324
J 2
(-623 3650);
DISPLAY 0.872340 (-623 3650);
PAINT GREEN (-623 3650);
DISPLAY INVISIBLE (-623 3650);
FORCEADD TAP..1
R 2
(-775 3600);
FORCEPROP 3 LASTPIN (-725 3600) SIG_NAME P3E_PCH_E1S_TX_C_DN<1>
J 0
(-715 3610);
DISPLAY 0.659574 (-715 3610);
PAINT MONO (-715 3610);
DISPLAY INVISIBLE (-715 3610);
FORCEPROP 1 LASTPIN (-725 3600) BN 1
J 2
(-713 3608);
DISPLAY 0.680851 (-713 3608);
PAINT GREEN (-713 3608);
FORCEPROP 2 LAST CDS_LIB standard
J 0
(-775 3600);
PAINT MONO (-775 3600);
DISPLAY INVISIBLE (-775 3600);
FORCEPROP 1 LAST BODY_TYPE PLUMBING
J 2
(-775 3650);
DISPLAY 0.872340 (-775 3650);
PAINT GREEN (-775 3650);
DISPLAY INVISIBLE (-775 3650);
FORCEPROP 1 LAST HDL_TAP TRUE
J 2
(-1100 3475);
DISPLAY 0.872340 (-1100 3475);
PAINT GREEN (-1100 3475);
DISPLAY INVISIBLE (-1100 3475);
FORCEPROP 1 LAST PATH I325
J 2
(-773 3600);
DISPLAY 0.872340 (-773 3600);
PAINT GREEN (-773 3600);
DISPLAY INVISIBLE (-773 3600);
FORCEADD UNIVERSAL_GND..1
(-3350 850);
FORCEPROP 3 LASTPIN (-3350 900) SIG_NAME GND\g
J 0
(-3340 910);
DISPLAY 0.659574 (-3340 910);
PAINT MONO (-3340 910);
DISPLAY INVISIBLE (-3340 910);
FORCEPROP 2 LAST CDS_LIB logical_power
J 0
(-3350 850);
DISPLAY INVISIBLE (-3350 850);
FORCEPROP 1 LAST PATH I326
J 0
(-3275 850);
DISPLAY 0.872340 (-3275 850);
PAINT AQUA (-3275 850);
DISPLAY INVISIBLE (-3275 850);
FORCEPROP 1 LAST HDL_POWER GND
J 1
(-3325 775);
DISPLAY 0.872340 (-3325 775);
PAINT GREEN (-3325 775);
DISPLAY INVISIBLE (-3325 775);
FORCEADD Q_CAP..1
R 2
(-3350 1075);
FORCEPROP 1 LAST PART_NUMBER CH4104K1B00
J 2
(-3400 925);
DISPLAY 0.510638 (-3400 925);
DISPLAY INVISIBLE (-3400 925);
FORCEPROP 1 LAST MATERIAL X7R
J 2
(-3400 975);
DISPLAY 0.510638 (-3400 975);
FORCEPROP 1 LAST TOLERANCE 10%
J 2
(-3400 1025);
DISPLAY 0.510638 (-3400 1025);
FORCEPROP 1 LAST PACK_TYPE 0402
J 2
(-3400 875);
DISPLAY 0.510638 (-3400 875);
FORCEPROP 1 LAST VOLTAGE 25V
J 2
(-3400 1075);
DISPLAY 0.510638 (-3400 1075);
FORCEPROP 1 LAST VALUE 0.1UF
J 2
(-3400 1125);
DISPLAY 0.510638 (-3400 1125);
FORCEPROP 1 LAST $LOCATION C2378
J 2
(-3400 1175);
DISPLAY 0.978723 (-3400 1175);
FORCEPROP 1 LASTPIN (-3350 1175) $PN 1
J 2
(-3360 1155);
DISPLAY 0.787234 (-3360 1155);
PAINT MONO (-3360 1155);
FORCEPROP 1 LASTPIN (-3350 975) $PN 2
J 2
(-3360 955);
DISPLAY 0.787234 (-3360 955);
PAINT MONO (-3360 955);
FORCEPROP 2 LAST CDS_LIB pure_quanta
J 0
(-3350 1075);
DISPLAY INVISIBLE (-3350 1075);
FORCEPROP 1 LAST PATH I327
J 2
(-3400 1225);
DISPLAY 0.978723 (-3400 1225);
PAINT WHITE (-3400 1225);
DISPLAY INVISIBLE (-3400 1225);
FORCEPROP 0 LAST CDS_LOCATION C2378
J 0
(-3400 1225);
DISPLAY 1.021277 (-3400 1225);
DISPLAY INVISIBLE (-3400 1225);
FORCEPROP 0 LAST $SEC 1
J 0
(-3400 1225);
DISPLAY 0.680851 (-3400 1225);
PAINT MONO (-3400 1225);
DISPLAY INVISIBLE (-3400 1225);
FORCEPROP 0 LAST CDS_SEC 1
J 0
(-3400 1225);
DISPLAY 1.021277 (-3400 1225);
DISPLAY INVISIBLE (-3400 1225);
FORCEADD UNIVERSAL_POWER..1
(-3350 1400);
FORCEPROP 3 LASTPIN (-3350 1350) SIG_NAME P3V3_E1S_0\g
J 0
(-3340 1360);
DISPLAY 0.659574 (-3340 1360);
PAINT MONO (-3340 1360);
DISPLAY INVISIBLE (-3340 1360);
FORCEPROP 1 LAST HDL_POWER P3V3_E1S_0
J 1
(-3350 1450);
DISPLAY 0.872340 (-3350 1450);
PAINT GREEN (-3350 1450);
FORCEPROP 2 LAST CDS_LIB logical_power
J 0
(-3350 1400);
DISPLAY INVISIBLE (-3350 1400);
FORCEPROP 1 LAST PATH I328
J 0
(-3300 1425);
DISPLAY 0.872340 (-3300 1425);
PAINT AQUA (-3300 1425);
DISPLAY INVISIBLE (-3300 1425);
FORCEADD APX80929SAG7..1
R 2
(-2650 1250);
FORCEPROP 1 LAST PART_NUMBER AL080929000
J 2
(-2425 1517);
DISPLAY 0.723404 (-2425 1517);
PAINT GREEN (-2425 1517);
DISPLAY INVISIBLE (-2425 1517);
FORCEPROP 2 LAST PART_TYPE SMLF
J 2
(-2425 1675);
DISPLAY 1.021277 (-2425 1675);
FORCEPROP 1 LAST MATERIAL IC
J 2
(-2425 1460);
DISPLAY 0.723404 (-2425 1460);
PAINT GREEN (-2425 1460);
FORCEPROP 2 LAST VALUE APX809-29SAG-7
J 2
(-2425 1625);
DISPLAY 1.021277 (-2425 1625);
FORCEPROP 1 LAST $LOCATION U336
J 2
(-2425 1569);
DISPLAY 0.723404 (-2425 1569);
PAINT GREEN (-2425 1569);
FORCEPROP 0 LASTPIN (-2275 1350) $PN 1
J 0
(-2265 1360);
DISPLAY 0.680851 (-2265 1360);
PAINT MONO (-2265 1360);
FORCEPROP 0 LASTPIN (-2275 1150) $PN 2
J 0
(-2265 1160);
DISPLAY 0.680851 (-2265 1160);
PAINT MONO (-2265 1160);
FORCEPROP 0 LASTPIN (-3025 1250) $PN 3
J 2
(-3035 1260);
DISPLAY 0.680851 (-3035 1260);
PAINT MONO (-3035 1260);
FORCEPROP 2 LAST CDS_LIB pure_quanta
J 0
(-2650 1250);
DISPLAY INVISIBLE (-2650 1250);
FORCEPROP 1 LAST PATH I329
J 2
(-2875 1050);
DISPLAY 0.723404 (-2875 1050);
PAINT GREEN (-2875 1050);
DISPLAY INVISIBLE (-2875 1050);
FORCEPROP 1 LAST CDS_LMAN_SYM_OUTLINE -225,200,225,-200
J 2
(-2650 1250);
DISPLAY 0.468085 (-2650 1250);
PAINT GREEN (-2650 1250);
DISPLAY INVISIBLE (-2650 1250);
FORCEPROP 1 LAST NEEDS_NO_SIZE TRUE
J 2
(-2875 1090);
DISPLAY 0.723404 (-2875 1090);
PAINT GREEN (-2875 1090);
DISPLAY INVISIBLE (-2875 1090);
FORCEPROP 0 LAST CDS_LOCATION U336
J 0
(-2425 1725);
DISPLAY 1.021277 (-2425 1725);
DISPLAY INVISIBLE (-2425 1725);
FORCEPROP 0 LAST $SEC 1
J 0
(-2425 1725);
DISPLAY 0.680851 (-2425 1725);
PAINT MONO (-2425 1725);
DISPLAY INVISIBLE (-2425 1725);
FORCEPROP 0 LAST CDS_SEC 1
J 0
(-2425 1725);
DISPLAY 1.021277 (-2425 1725);
DISPLAY INVISIBLE (-2425 1725);
FORCEADD UNIVERSAL_GND..1
(-2150 1225);
FORCEPROP 3 LASTPIN (-2150 1275) SIG_NAME GND\g
J 0
(-2140 1285);
DISPLAY 0.659574 (-2140 1285);
PAINT MONO (-2140 1285);
DISPLAY INVISIBLE (-2140 1285);
FORCEPROP 2 LAST CDS_LIB logical_power
J 0
(-2150 1225);
DISPLAY INVISIBLE (-2150 1225);
FORCEPROP 1 LAST PATH I330
J 0
(-2075 1225);
DISPLAY 0.872340 (-2075 1225);
PAINT AQUA (-2075 1225);
DISPLAY INVISIBLE (-2075 1225);
FORCEPROP 1 LAST HDL_POWER GND
J 1
(-2125 1150);
DISPLAY 0.872340 (-2125 1150);
PAINT GREEN (-2125 1150);
DISPLAY INVISIBLE (-2125 1150);
FORCEADD Q_RES..1
(-1400 1150);
FORCEPROP 1 LAST PART_NUMBER CS04992FB07
J 0
(-1300 1125);
DISPLAY 0.404255 (-1300 1125);
DISPLAY INVISIBLE (-1300 1125);
FORCEPROP 1 LAST VALUE 49.9
J 2
(-1175 1150);
DISPLAY 0.510638 (-1175 1150);
FORCEPROP 1 LAST MATERIAL CHIP
J 0
(-1550 1125);
DISPLAY 0.404255 (-1550 1125);
FORCEPROP 1 LAST $LOCATION R4767
J 0
(-1625 1150);
DISPLAY 0.638298 (-1625 1150);
FORCEPROP 1 LASTPIN (-1500 1150) $PN 1
J 0
(-1488 1162);
DISPLAY 0.787234 (-1488 1162);
PAINT MONO (-1488 1162);
FORCEPROP 1 LASTPIN (-1300 1150) $PN 2
J 0
(-1338 1162);
DISPLAY 0.787234 (-1338 1162);
PAINT MONO (-1338 1162);
FORCEPROP 2 LAST CDS_LIB pure_quanta
J 0
(-1400 1150);
DISPLAY INVISIBLE (-1400 1150);
FORCEPROP 1 LAST PATH I331
J 0
(-1450 1300);
DISPLAY 0.978723 (-1450 1300);
PAINT WHITE (-1450 1300);
DISPLAY INVISIBLE (-1450 1300);
FORCEPROP 1 LAST PACK_TYPE 0402LF
J 0
(-1100 1150);
DISPLAY 0.510638 (-1100 1150);
DISPLAY INVISIBLE (-1100 1150);
FORCEPROP 1 LAST TOLERANCE 1%
J 0
(-1175 1150);
DISPLAY 0.510638 (-1175 1150);
DISPLAY INVISIBLE (-1175 1150);
FORCEPROP 1 LAST WATTAGE 1/16W
J 2
(-1100 1100);
DISPLAY 0.404255 (-1100 1100);
DISPLAY INVISIBLE (-1100 1100);
FORCEPROP 0 LAST CDS_LOCATION R4767
J 0
(-1625 1200);
DISPLAY 1.021277 (-1625 1200);
DISPLAY INVISIBLE (-1625 1200);
FORCEPROP 0 LAST $SEC 1
J 0
(-1625 1200);
DISPLAY 0.680851 (-1625 1200);
PAINT MONO (-1625 1200);
DISPLAY INVISIBLE (-1625 1200);
FORCEPROP 0 LAST CDS_SEC 1
J 0
(-1625 1200);
DISPLAY 1.021277 (-1625 1200);
DISPLAY INVISIBLE (-1625 1200);
FORCEADD OFFPAGE..2
(-475 1150);
FORCEPROP 2 LAST $XR0 216 
J 0
(-286 1150);
DISPLAY 0.638298 (-286 1150);
PAINT MONO (-286 1150);
FORCEPROP 2 LAST CDS_LIB standard
J 0
(-475 1150);
DISPLAY INVISIBLE (-475 1150);
FORCEPROP 2 LAST PATH I332
J 0
(-300 1225);
DISPLAY 1.021277 (-300 1225);
DISPLAY INVISIBLE (-300 1225);
FORCEPROP 1 LAST COMMENT_BODY TRUE
J 0
(-520 1055);
DISPLAY 0.872340 (-520 1055);
PAINT GREEN (-520 1055);
DISPLAY INVISIBLE (-520 1055);
FORCEPROP 1 LAST OFFPAGE TRUE
J 0
(-150 1025);
DISPLAY 0.872340 (-150 1025);
DISPLAY INVISIBLE (-150 1025);
FORCEADD DNS..2
(-3470 3420);
PAINT RED (-3470 3420);
FORCEPROP 2 LAST CDS_LIB mstr_misc
J 0
(-3470 3420);
DISPLAY INVISIBLE (-3470 3420);
FORCEPROP 1 LAST COMMENT_BODY TRUE
J 0
(-3470 3420);
DISPLAY INVISIBLE (-3470 3420);
FORCEADD DNS..2
(2775 -225);
PAINT RED (2775 -225);
FORCEPROP 1 LAST COMMENT_BODY TRUE
R 1
J 0
(2850 -450);
DISPLAY 0.872340 (2850 -450);
PAINT GREEN (2850 -450);
DISPLAY INVISIBLE (2850 -450);
FORCEPROP 2 LAST CDS_LIB mstr_misc
J 0
(2775 -225);
DISPLAY INVISIBLE (2775 -225);
FORCEADD CAD_NOTE..1
(2950 3225);
FORCEPROP 0 LAST S1 PLACE THE BULK CAPS CLOSE TO SLOT
J 0
(2825 3100);
DISPLAY 0.808511 (2825 3100);
PAINT WHITE (2825 3100);
FORCEPROP 2 LAST CDS_LIB logical_power
J 0
(2950 3225);
PAINT MONO (2950 3225);
DISPLAY INVISIBLE (2950 3225);
FORCEPROP 1 LAST COMMENT_BODY TRUE
J 0
(2975 3325);
DISPLAY 0.978723 (2975 3325);
DISPLAY INVISIBLE (2975 3325);
FORCEADD DNS..2
(3850 3825);
PAINT RED (3850 3825);
FORCEPROP 2 LAST CDS_LIB mstr_misc
J 0
(3850 3825);
DISPLAY INVISIBLE (3850 3825);
FORCEPROP 1 LAST COMMENT_BODY TRUE
J 0
(3850 3825);
DISPLAY INVISIBLE (3850 3825);
FORCEADD DESIGN_NOTE..1
(-3575 4800);
FORCEPROP 0 LAST S1 DP/DN SWAP TX[0:1] RX[0]
J 0
(-3775 4650);
DISPLAY 1.021277 (-3775 4650);
PAINT SKYBLUE (-3775 4650);
FORCEPROP 2 LAST CDS_LIB logical_power
J 0
(-3575 4800);
DISPLAY INVISIBLE (-3575 4800);
FORCEPROP 1 LAST COMMENT_BODY TRUE
J 0
(-3550 4900);
DISPLAY 0.978723 (-3550 4900);
DISPLAY INVISIBLE (-3550 4900);
FORCEADD QUANTA_TITLE_BLOCK_C..1
(5025 -1275);
FORCEPROP 0 LAST CDS_CON_LAST_MODIFIED Fri Aug 25 14:03:04 2023
J 0
(3140 -1260);
DISPLAY INVISIBLE (3140 -1260);
FORCEPROP 1 LAST CUSTOM_TXT_CDS <CON_LAST_MODIFIED>
J 0
(3140 -1260);
DISPLAY 0.978723 (3140 -1260);
FORCEPROP 2 LAST CUSTOM_TXT_CDS <XR_PAGE_TITLE>
J 0
(-2865 3975);
DISPLAY 0.638298 (-2865 3975);
PAINT PINK (-2865 3975);
DISPLAY INVISIBLE (-2865 3975);
FORCEPROP 1 LAST CUSTOM_TXT_CDS <NAME_2>
J 0
(1850 -1225);
FORCEPROP 1 LAST CUSTOM_TXT_CDS <NAME_1>
J 0
(1850 -1100);
FORCEPROP 1 LAST CUSTOM_TXT_CDS <Q_NUMBER>
J 0
(3622 -1172);
DISPLAY 1.212766 (3622 -1172);
FORCEPROP 1 LAST CUSTOM_TXT_CDS <Q_PROJ>
J 0
(2643 -1173);
DISPLAY 1.212766 (2643 -1173);
FORCEPROP 1 LAST CUSTOM_TXT_CDS <Q_REV>
J 0
(4841 -1172);
DISPLAY 1.212766 (4841 -1172);
FORCEPROP 1 LAST CUSTOM_TXT_CDS <CON_PAGE_NUM> OF <CON_TOTAL_PAGES>
J 0
(4579 -1257);
DISPLAY 0.978723 (4579 -1257);
FORCEPROP 1 LAST Q_TITLE PCH - E1S - 0 CONN
J 0
(-4200 -1200);
DISPLAY 2.446809 (-4200 -1200);
PAINT GREEN (-4200 -1200);
FORCEPROP 1 LAST Q_DEPT 
J 1
(1262 -1226);
DISPLAY 1.957447 (1262 -1226);
PAINT GREEN (1262 -1226);
FORCEPROP 2 LAST CDS_XR_PAGE_TITLE CR-191 : @S9S_MB_2U_LIB.S9S_MB_2U(SCH_1):PAGE191
J 0
(-2865 3975);
DISPLAY 0.638298 (-2865 3975);
PAINT PINK (-2865 3975);
DISPLAY INVISIBLE (-2865 3975);
FORCEPROP 1 LAST COMMENT_BODY TRUE
J 0
(5037 -1288);
DISPLAY 0.978723 (5037 -1288);
PAINT GREEN (5037 -1288);
DISPLAY INVISIBLE (5037 -1288);
FORCEPROP 2 LAST PAGE_BORDER TRUE
J 0
(-2865 3975);
DISPLAY 0.638298 (-2865 3975);
PAINT PINK (-2865 3975);
DISPLAY INVISIBLE (-2865 3975);
FORCEPROP 1 LAST CDS_LMAN_SYM_OUTLINE -9475,6775,100,-125
J 0
(5025 -1275);
DISPLAY 0.468085 (5025 -1275);
PAINT GREEN (5025 -1275);
DISPLAY INVISIBLE (5025 -1275);
FORCEPROP 2 LAST CDS_LIB pure_quanta
J 0
(5025 -1275);
DISPLAY INVISIBLE (5025 -1275);
WIRE 17 -1 (1725 3625)(1725 3475);
WIRE 17 -1 (1725 3825)(1725 3625);
WIRE 17 -1 (1725 3475)(1725 3325);
WIRE 17 -1 (2850 3825)(1725 3825);
FORCEPROP 2 LAST SIG_NAME P3E_PCH_E1S_RX_DP<3:0>
J 0
(1965 3835);
DISPLAY 0.510638 (1965 3835);
PAINT WHITE (1965 3835);
WIRE 17 -1 (-675 3675)(-675 3825);
WIRE 17 -1 (-675 3475)(-675 3675);
WIRE 17 -1 (-1625 3825)(-675 3825);
FORCEPROP 2 LAST SIG_NAME P3E_PCH_E1S_TX_C_DP<3:0>
J 0
(-1560 3835);
DISPLAY 0.553191 (-1560 3835);
PAINT WHITE (-1560 3835);
WIRE 17 -1 (-825 3625)(-825 3775);
WIRE 17 -1 (-825 3525)(-825 3625);
WIRE 17 -1 (-825 3775)(-1625 3775);
FORCEPROP 2 LAST SIG_NAME P3E_PCH_E1S_TX_C_DN<3:0>
J 0
(-1560 3785);
DISPLAY 0.553191 (-1560 3785);
PAINT WHITE (-1560 3785);
WIRE 17 -1 (-825 3525)(-825 3375);
WIRE 17 -1 (-675 3475)(-675 3325);
WIRE 17 -1 (1875 3775)(1875 3675);
WIRE 17 -1 (2850 3775)(1875 3775);
FORCEPROP 2 LAST SIG_NAME P3E_PCH_E1S_RX_DN<3:0>
J 0
(1965 3785);
DISPLAY 0.510638 (1965 3785);
PAINT WHITE (1965 3785);
WIRE 17 -1 (1875 3525)(1875 3375);
WIRE 17 -1 (1875 3675)(1875 3525);
WIRE 16 -1 (950 75)(950 -25);
WIRE 16 -1 (2325 3125)(2325 3050);
WIRE 16 -1 (2775 100)(2775 25);
WIRE 16 -1 (-650 4950)(-650 4150);
WIRE 16 -1 (4350 3125)(4350 3050);
WIRE 16 -1 (-350 5125)(-350 4700);
WIRE 16 -1 (3850 1625)(3850 1575);
WIRE 16 -1 (2675 1950)(2675 1900);
WIRE 16 -1 (1800 1725)(1800 1625);
WIRE 16 -1 (-3475 3550)(-3475 3650);
WIRE 16 -1 (-3350 1250)(-3350 1350);
WIRE 16 -1 (-3350 1175)(-3350 1250);
WIRE 16 -1 (-3025 1250)(-3350 1250);
WIRE 16 -1 (2300 4775)(2300 4725);
WIRE 16 -1 (-1925 4625)(-1925 4725);
WIRE 16 -1 (3775 4800)(3775 4750);
WIRE 16 -1 (3850 3675)(3850 3750);
WIRE 16 -1 (1400 3000)(1400 3150);
WIRE 16 -1 (-400 3000)(-400 3150);
WIRE 16 -1 (-175 -600)(-175 -775);
WIRE 16 -1 (-175 -600)(-75 -600);
WIRE 16 -1 (950 -300)(950 -375);
WIRE 16 -1 (3275 2525)(3275 2600);
WIRE 16 -1 (4600 2525)(4600 2600);
WIRE 16 -1 (3675 625)(3675 525);
WIRE 16 -1 (4350 550)(4350 500);
WIRE 16 -1 (3850 1300)(3850 1225);
WIRE 16 -1 (2675 1025)(2675 950);
WIRE 16 -1 (-3475 2750)(-3475 2850);
WIRE 16 -1 (-2150 1350)(-2150 1275);
WIRE 16 -1 (-2275 1350)(-2150 1350);
WIRE 16 -1 (-3350 975)(-3350 900);
WIRE 16 2175 (-3675 1825)(-150 1825);
WIRE 16 2175 (-150 1825)(-150 750);
WIRE 16 2175 (-3675 1825)(-3675 750);
WIRE 16 2175 (-3675 750)(-150 750);
WIRE 16 -1 (2825 4100)(1225 4100);
FORCEPROP 2 LAST SIG_NAME E1S_0_PRSNT_N
J 0
(1590 4110);
DISPLAY 0.553191 (1590 4110);
PAINT WHITE (1590 4110);
WIRE 16 2175 (3550 5025)(4100 5025);
WIRE 16 2175 (4100 5025)(4100 4425);
WIRE 16 2175 (3550 5025)(3550 4425);
WIRE 16 2175 (3550 4425)(4100 4425);
WIRE 16 2175 (-2150 4700)(-1725 4700);
WIRE 16 2175 (-1725 4875)(-1725 4700);
WIRE 16 2175 (-2150 4875)(-2150 4700);
WIRE 16 2175 (-2150 4875)(-1725 4875);
WIRE 16 -1 (-650 4150)(-225 4150);
WIRE 16 -1 (-350 4700)(-225 4700);
WIRE 16 -1 (-350 4650)(-350 4700);
WIRE 16 -1 (-350 4650)(-225 4650);
WIRE 16 -1 (-350 4600)(-225 4600);
WIRE 16 -1 (-350 4600)(-350 4650);
WIRE 16 -1 (-350 4550)(-350 4600);
WIRE 16 -1 (-350 4550)(-225 4550);
WIRE 16 -1 (-350 4550)(-350 4500);
WIRE 16 -1 (-350 4500)(-225 4500);
WIRE 16 -1 (-350 4450)(-350 4500);
WIRE 16 -1 (-350 4450)(-225 4450);
WIRE 16 2175 (2075 4925)(2575 4925);
WIRE 16 2175 (2575 4925)(2575 4425);
WIRE 16 2175 (2075 4925)(2075 4425);
WIRE 16 2175 (2075 4425)(2575 4425);
WIRE 16 -1 (3850 3950)(3850 4150);
WIRE 16 -1 (4025 4150)(3850 4150);
WIRE 16 -1 (3775 4550)(3775 4150);
WIRE 16 -1 (3850 4150)(3775 4150);
WIRE 16 -1 (1225 4150)(3775 4150);
FORCEPROP 2 LAST SIG_NAME E1S_0_PERST1_CLKREQ_N
J 0
(1590 4160);
DISPLAY 0.553191 (1590 4160);
PAINT WHITE (1590 4160);
WIRE 16 -1 (1225 3950)(2775 3950);
FORCEPROP 2 LAST SIG_NAME TP_CLK_100M_E1S_0_DN
J 0
(1590 3960);
DISPLAY 0.553191 (1590 3960);
PAINT WHITE (1590 3960);
WIRE 16 -1 (1225 4200)(2825 4200);
FORCEPROP 2 LAST SIG_NAME E1S_0_LED_ACT_N
J 0
(1590 4210);
DISPLAY 0.553191 (1590 4210);
PAINT WHITE (1590 4210);
WIRE 16 -1 (1225 4300)(2825 4300);
FORCEPROP 2 LAST SIG_NAME SMB_E1S_3V3AUX_ISO_SDA
J 0
(1590 4310);
DISPLAY 0.553191 (1590 4310);
PAINT WHITE (1590 4310);
WIRE 16 -1 (1225 4350)(2825 4350);
FORCEPROP 2 LAST SIG_NAME SMB_E1S_3V3AUX_ISO_SCL
J 0
(1590 4360);
DISPLAY 0.553191 (1590 4360);
PAINT WHITE (1590 4360);
WIRE 16 -1 (2300 4525)(2300 4250);
WIRE 16 -1 (2825 4250)(2300 4250);
WIRE 16 -1 (1225 4250)(2300 4250);
FORCEPROP 2 LAST SIG_NAME RST_SMB_E1S_0_N
J 0
(1590 4260);
DISPLAY 0.553191 (1590 4260);
PAINT WHITE (1590 4260);
WIRE 16 -1 (-1625 4300)(-225 4300);
FORCEPROP 2 LAST SIG_NAME TP_E1S_0_RFU
J 0
(-1560 4310);
DISPLAY 0.553191 (-1560 4310);
PAINT WHITE (-1560 4310);
WIRE 16 -1 (-1625 4350)(-225 4350);
FORCEPROP 2 LAST SIG_NAME TP_E1S_0_MFG
J 0
(-1560 4360);
DISPLAY 0.553191 (-1560 4360);
PAINT WHITE (-1560 4360);
WIRE 16 -1 (-225 4250)(-1925 4250);
FORCEPROP 2 LAST SIG_NAME PU_E1S_0_DUALPORT_EN_N
J 0
(-1560 4260);
DISPLAY 0.553191 (-1560 4260);
PAINT WHITE (-1560 4260);
WIRE 16 -1 (-1925 4425)(-1925 4250);
WIRE 16 -1 (-1900 4200)(-225 4200);
FORCEPROP 2 LAST SIG_NAME RST_PCIE_PCH_E1S_PERST_N
J 0
(-1560 4210);
DISPLAY 0.553191 (-1560 4210);
PAINT WHITE (-1560 4210);
WIRE 16 -1 (-1625 4100)(-225 4100);
FORCEPROP 2 LAST SIG_NAME E1S_0_PWRDIS
J 0
(-1560 4110);
DISPLAY 0.553191 (-1560 4110);
PAINT WHITE (-1560 4110);
WIRE 16 -1 (1225 3900)(2775 3900);
FORCEPROP 2 LAST SIG_NAME TP_CLK_100M_E1S_0_DP
J 0
(1590 3910);
DISPLAY 0.553191 (1590 3910);
PAINT WHITE (1590 3910);
WIRE 16 -1 (1225 3800)(1625 3800);
WIRE 16 -1 (1225 3750)(1775 3750);
WIRE 16 -1 (1225 3150)(1400 3150);
WIRE 16 -1 (1225 3250)(1400 3250);
WIRE 16 -1 (1400 3150)(1400 3250);
WIRE 16 -1 (1225 3400)(1400 3400);
WIRE 16 -1 (1400 3400)(1400 3250);
WIRE 16 -1 (1225 3550)(1400 3550);
WIRE 16 -1 (1400 3550)(1400 3400);
WIRE 16 -1 (1400 3700)(1400 3550);
WIRE 16 -1 (1225 3700)(1400 3700);
WIRE 16 -1 (1225 3850)(1400 3850);
WIRE 16 -1 (1400 3850)(1400 3700);
WIRE 16 -1 (1225 4000)(1400 4000);
WIRE 16 -1 (1400 3850)(1400 4000);
WIRE 16 -1 (1400 4450)(1400 4000);
WIRE 16 -1 (1225 4450)(1400 4450);
WIRE 16 -1 (1225 4500)(1400 4500);
WIRE 16 -1 (1400 4450)(1400 4500);
WIRE 16 -1 (1225 4550)(1400 4550);
WIRE 16 -1 (1400 4550)(1400 4500);
WIRE 16 -1 (1225 4600)(1400 4600);
WIRE 16 -1 (1400 4550)(1400 4600);
WIRE 16 -1 (1400 4600)(1400 4650);
WIRE 16 -1 (1225 4650)(1400 4650);
WIRE 16 -1 (1400 4650)(1400 4700);
WIRE 16 -1 (1225 4700)(1400 4700);
WIRE 16 -1 (1225 3600)(1625 3600);
WIRE 16 -1 (-1500 1150)(-2275 1150);
FORCEPROP 2 LAST SIG_NAME HP_E1S_0_P3V3_PWRGD
J 0
(-2185 1160);
DISPLAY 0.553191 (-2185 1160);
PAINT WHITE (-2185 1160);
WIRE 16 -1 (-525 1150)(-1300 1150);
FORCEPROP 2 LAST SIG_NAME HP_E1S_0_P3V3_PWRGD_PLD
J 0
(-1160 1160);
DISPLAY 0.553191 (-1160 1160);
PAINT WHITE (-1160 1160);
WIRE 16 -1 (-3475 3175)(-3475 3050);
WIRE 16 -1 (-3475 3350)(-3475 3175);
WIRE 16 -1 (-3475 3175)(-2850 3175);
FORCEPROP 2 LAST SIG_NAME E1S_0_PWRDIS
J 0
(-3360 3185);
DISPLAY 0.638298 (-3360 3185);
PAINT WHITE (-3360 3185);
WIRE 16 -1 (2175 825)(1375 825);
FORCEPROP 2 LAST SIG_NAME FM_PS_EN_PLD_BUF1
J 0
(1490 835);
DISPLAY 0.553191 (1490 835);
PAINT WHITE (1490 835);
WIRE 16 -1 (3425 825)(2375 825);
FORCEPROP 2 LAST SIG_NAME FM_PS_EN_PLD_BUF1_R1
J 0
(2790 835);
DISPLAY 0.553191 (2790 835);
PAINT WHITE (2790 835);
WIRE 16 -1 (4350 750)(4350 875);
WIRE 16 -1 (4425 875)(4350 875);
WIRE 16 -1 (3925 875)(4350 875);
FORCEPROP 0 LAST CDS_PHYS_NET_NAME E1S_0_EN
J 0
(4240 917);
PAINT MONO (4240 917);
DISPLAY INVISIBLE (4240 917);
FORCEPROP 2 LAST SIG_NAME E1S_0_EN
J 0
(4040 885);
DISPLAY 0.553191 (4040 885);
PAINT WHITE (4040 885);
FORCEPROP 0 LAST $PHYS_NET_NAME RST_PCIE_M2_N
J 0
(4240 964);
PAINT MONO (4240 964);
DISPLAY INVISIBLE (4240 964);
WIRE 16 -1 (1800 1225)(1725 1225);
WIRE 16 -1 (1800 1425)(1800 1225);
WIRE 16 -1 (2475 1225)(1800 1225);
FORCEPROP 2 LAST SIG_NAME E1S_0_PRSNT_N
J 0
(1915 1235);
DISPLAY 0.553191 (1915 1235);
PAINT WHITE (1915 1235);
WIRE 16 -1 (2675 1425)(2675 1525);
WIRE 16 -1 (2675 1525)(2675 1700);
WIRE 16 -1 (3225 925)(3425 925);
WIRE 16 -1 (3225 1525)(2675 1525);
FORCEPROP 2 LAST SIG_NAME E1S_0_PRSNT
J 0
(2790 1535);
DISPLAY 0.553191 (2790 1535);
PAINT WHITE (2790 1535);
WIRE 16 -1 (3225 1525)(3225 925);
WIRE 16 -1 (3675 1125)(3675 1575);
WIRE 16 -1 (3850 1575)(3850 1500);
WIRE 16 -1 (3850 1575)(3675 1575);
WIRE 16 -1 (4350 3050)(4350 2925);
WIRE 16 -1 (4350 3050)(4600 3050);
WIRE 16 -1 (4600 3050)(4600 2925);
WIRE 16 -1 (4350 2725)(4350 2600);
WIRE 16 -1 (4350 2600)(4600 2600);
WIRE 16 -1 (4600 2600)(4600 2725);
WIRE 16 -1 (3275 2600)(3275 2725);
WIRE 16 -1 (3000 2600)(3000 2725);
WIRE 16 -1 (3000 2600)(3275 2600);
WIRE 16 -1 (2600 2600)(2600 2725);
WIRE 16 -1 (3000 2600)(2600 2600);
WIRE 16 -1 (2325 2600)(2600 2600);
WIRE 16 -1 (2325 2725)(2325 2600);
WIRE 16 -1 (2325 2925)(2325 3050);
WIRE 16 -1 (2325 3050)(2600 3050);
WIRE 16 -1 (2600 3050)(2600 2925);
WIRE 16 -1 (3000 3050)(2600 3050);
WIRE 16 -1 (3000 3050)(3000 2925);
WIRE 16 -1 (3000 3050)(3275 3050);
WIRE 16 -1 (3275 3050)(3275 2925);
WIRE 16 -1 (-400 3150)(-225 3150);
WIRE 16 -1 (-400 3250)(-400 3150);
WIRE 16 -1 (-400 3250)(-225 3250);
WIRE 16 -1 (-400 3400)(-400 3250);
WIRE 16 -1 (-400 3400)(-225 3400);
WIRE 16 -1 (-400 3400)(-400 3550);
WIRE 16 -1 (-400 3550)(-225 3550);
WIRE 16 -1 (-400 3550)(-400 3700);
WIRE 16 -1 (-400 3700)(-225 3700);
WIRE 16 -1 (-400 3700)(-400 3850);
WIRE 16 -1 (-400 3850)(-225 3850);
WIRE 16 -1 (-400 3850)(-400 4000);
WIRE 16 -1 (-225 4000)(-400 4000);
WIRE 16 -1 (2775 25)(2775 -100);
WIRE 16 -1 (3050 25)(3050 -100);
WIRE 16 -1 (3050 25)(2775 25);
WIRE 16 -1 (950 -25)(950 -100);
WIRE 16 -1 (950 -25)(700 -25);
WIRE 16 -1 (700 -25)(700 -600);
WIRE 16 -1 (575 -600)(700 -600);
WIRE 16 -1 (-725 3600)(-225 3600);
WIRE 16 -1 (1225 3500)(1775 3500);
WIRE 16 -1 (-525 -550)(-900 -550);
FORCEPROP 0 LAST CDS_PHYS_NET_NAME RST_PCIE_PCH_DEV_PERST_N
J 0
(-875 -508);
PAINT MONO (-875 -508);
DISPLAY INVISIBLE (-875 -508);
FORCEPROP 0 LAST SIG_NAME RST_SMB_E1S_N
J 0
(-585 -540);
DISPLAY 0.702128 (-585 -540);
PAINT WHITE (-585 -540);
WIRE 16 -1 (-75 -550)(-525 -550);
WIRE 16 -1 (-525 -550)(-525 -650);
WIRE 16 -1 (-525 -650)(-75 -650);
WIRE 16 -1 (-1625 3900)(-225 3900);
FORCEPROP 2 LAST SIG_NAME CLK_100M_E1S_0_DP
J 0
(-1560 3910);
DISPLAY 0.553191 (-1560 3910);
PAINT WHITE (-1560 3910);
WIRE 16 -1 (-1625 3950)(-225 3950);
FORCEPROP 2 LAST SIG_NAME CLK_100M_E1S_0_DN
J 0
(-1560 3960);
DISPLAY 0.553191 (-1560 3960);
PAINT WHITE (-1560 3960);
WIRE 16 -1 (-725 3500)(-225 3500);
WIRE 16 -1 (1225 3350)(1775 3350);
WIRE 16 -1 (1225 3300)(1625 3300);
WIRE 16 2175 (2575 -375)(3025 -375);
WIRE 16 2175 (3025 275)(3025 -375);
WIRE 16 2175 (2575 275)(2575 -375);
WIRE 16 2175 (2575 275)(3025 275);
WIRE 16 -1 (1225 3650)(1775 3650);
WIRE 16 -1 (1850 -550)(2775 -550);
FORCEPROP 2 LAST SIG_NAME RST_SMB_E1S_0_N
J 0
(2215 -540);
DISPLAY 0.702128 (2215 -540);
PAINT WHITE (2215 -540);
WIRE 16 -1 (2775 -550)(3175 -550);
WIRE 16 -1 (2775 -300)(2775 -550);
WIRE 16 -1 (-3100 4200)(-2100 4200);
FORCEPROP 2 LAST SIG_NAME RST_PCIE_PCH_DEV_PERST_E1S_R_N
J 0
(-3035 4210);
DISPLAY 0.553191 (-3035 4210);
PAINT WHITE (-3035 4210);
WIRE 16 -1 (-575 3300)(-225 3300);
WIRE 16 -1 (-575 3450)(-225 3450);
WIRE 16 -1 (-1100 -550)(-1675 -550);
FORCEPROP 0 LAST CDS_PHYS_NET_NAME RST_SMB_SWITCH_N
J 0
(-1650 -508);
PAINT MONO (-1650 -508);
DISPLAY INVISIBLE (-1650 -508);
FORCEPROP 0 LAST SIG_NAME RST_SMB_SWITCH_N
J 0
(-1635 -540);
DISPLAY 0.702128 (-1635 -540);
PAINT WHITE (-1635 -540);
WIRE 16 -1 (575 -550)(1650 -550);
FORCEPROP 0 LAST CDS_PHYS_NET_NAME RST_PCIE_CPU0_BUF_E1S_0_PERST_N
J 0
(600 -508);
PAINT MONO (600 -508);
DISPLAY INVISIBLE (600 -508);
FORCEPROP 0 LAST SIG_NAME RST_SMB_BUF_E1S_0_N
J 0
(765 -540);
DISPLAY 0.702128 (765 -540);
PAINT WHITE (765 -540);
WIRE 16 -1 (575 -650)(1650 -650);
FORCEPROP 0 LAST CDS_PHYS_NET_NAME RST_PCIE_CPU0_BUF_E1S_1_PERST_N
J 0
(600 -608);
PAINT MONO (600 -608);
DISPLAY INVISIBLE (600 -608);
FORCEPROP 0 LAST SIG_NAME SMB_PCIE_E1S_ISO_EN_R2
J 0
(765 -640);
DISPLAY 0.702128 (765 -640);
PAINT WHITE (765 -640);
WIRE 16 -1 (1850 -650)(3050 -650);
FORCEPROP 2 LAST SIG_NAME SMB_PCIE_E1S_ISO_EN
J 0
(2215 -640);
DISPLAY 0.702128 (2215 -640);
PAINT WHITE (2215 -640);
WIRE 16 -1 (3050 -650)(3175 -650);
WIRE 16 -1 (3050 -300)(3050 -650);
WIRE 16 -1 (-225 3350)(-725 3350);
WIRE 16 -1 (-575 3650)(-225 3650);
WIRE 16 -1 (-725 3750)(-225 3750);
WIRE 16 -1 (-575 3800)(-225 3800);
WIRE 16 -1 (1225 3450)(1625 3450);
DOT 1 (3775 4150);
DOT 1 (2300 4250);
DOT 1 (2775 25);
DOT 1 (2325 3050);
DOT 1 (1400 4650);
DOT 1 (1400 3850);
DOT 1 (1400 3550);
DOT 1 (-525 -550);
DOT 1 (2775 -550);
DOT 1 (3050 -650);
DOT 1 (950 -25);
DOT 1 (2600 2600);
DOT 1 (3000 2600);
DOT 1 (3000 3050);
DOT 1 (3275 2600);
DOT 1 (4600 2600);
DOT 1 (4350 3050);
DOT 1 (2600 3050);
DOT 1 (-400 3250);
DOT 1 (-400 3400);
DOT 1 (-400 3700);
DOT 1 (-350 4500);
DOT 1 (-350 4550);
DOT 1 (-350 4700);
DOT 1 (-350 4650);
DOT 1 (-400 3150);
DOT 1 (1400 3150);
DOT 1 (1400 3250);
DOT 1 (3850 4150);
DOT 1 (1400 4500);
DOT 1 (1400 4550);
DOT 1 (1400 4600);
DOT 1 (1400 4450);
DOT 1 (1400 3700);
DOT 1 (1400 3400);
DOT 1 (-400 3850);
DOT 1 (-400 3550);
DOT 1 (1400 4000);
DOT 1 (-350 4600);
DOT 1 (3850 1575);
DOT 1 (2675 1525);
DOT 1 (4350 875);
DOT 1 (1800 1225);
DOT 1 (-3475 3175);
DOT 1 (-3350 1250);
FORCENOTE
20220805 ADD C2378,R4767,U336
(-2550 1850) 0;
DISPLAY LEFT (-2550 1850);
DISPLAY 1.021277 (-2550 1850);
PAINT PINK (-2550 1850);
FORCENOTE
PUSH PULL OUTPUT
(-2950 975) 0;
DISPLAY LEFT (-2950 975);
DISPLAY 0.808511 (-2950 975);
PAINT PINK (-2950 975);
FORCENOTE
20220805 CHANGE TO P3V3_E1S_0
(3075 5050) 0;
DISPLAY LEFT (3075 5050);
DISPLAY 1.021277 (3075 5050);
PAINT PINK (3075 5050);
FORCENOTE
20220804 CHANGE TO P3V3_E1S_0
(-2650 4900) 0;
DISPLAY LEFT (-2650 4900);
DISPLAY 1.021277 (-2650 4900);
PAINT PINK (-2650 4900);
FORCENOTE
20220804 POP R1673
(1850 4950) 0;
DISPLAY LEFT (1850 4950);
DISPLAY 1.021277 (1850 4950);
PAINT PINK (1850 4950);
FORCENOTE
20210904 MODIFY FOR GT
(-4250 5200) 0;
DISPLAY LEFT (-4250 5200);
DISPLAY 2.510638 (-4250 5200);
PAINT PINK (-4250 5200);
FORCENOTE
20220804 DEPOP R3773
(2350 300) 0;
DISPLAY LEFT (2350 300);
DISPLAY 1.021277 (2350 300);
PAINT PINK (2350 300);
QUIT
